FILE_TYPE = MACRO_DRAWING;
SET COLOR_WIRE YELLOW;
SET COLOR_PROP MONO;
SET COLOR_DOT WHITE;
SET COLOR_ARC YELLOW;
SET COLOR_BODY GREEN;
SET COLOR_NOTE MONO;
SET PROP_DISPLAY VALUE;
SET PAGE_NUMBER P186;
FORCEADD CAP_A..1
(10850 4675);
FORCEPROP 1 LASTPIN (10850 4775) $PN 1
J 0
(10860 4755);
DISPLAY 0.617021 (10860 4755);
PAINT ORANGE (10860 4755);
FORCEPROP 1 LASTPIN (10850 4575) $PN 2
J 0
(10860 4555);
DISPLAY 0.617021 (10860 4555);
PAINT ORANGE (10860 4555);
FORCEPROP 1 LAST MATERIAL X7R
J 0
(10900 4575);
DISPLAY 0.617021 (10900 4575);
PAINT SKYBLUE (10900 4575);
FORCEPROP 1 LAST VOLTAGE 16V
J 0
(10900 4675);
DISPLAY 0.617021 (10900 4675);
PAINT SKYBLUE (10900 4675);
FORCEPROP 1 LAST PACK_TYPE 0402V
J 0
(10900 4475);
DISPLAY 0.617021 (10900 4475);
PAINT SKYBLUE (10900 4475);
FORCEPROP 1 LAST TOLERANCE 10%
J 0
(10900 4625);
DISPLAY 0.617021 (10900 4625);
PAINT SKYBLUE (10900 4625);
FORCEPROP 1 LAST VALUE 0.1UF
J 0
(10900 4725);
DISPLAY 0.617021 (10900 4725);
PAINT SKYBLUE (10900 4725);
FORCEPROP 1 LAST PART_NUMBER A36096-030
J 0
(10900 4525);
DISPLAY 0.617021 (10900 4525);
PAINT BLUE (10900 4525);
FORCEPROP 1 LAST LOCATION C1M24
J 0
(10900 4775);
DISPLAY 0.617021 (10900 4775);
PAINT AQUA (10900 4775);
FORCEPROP 1 LAST PATH I10
J 0
(10900 4825);
DISPLAY 0.978723 (10900 4825);
PAINT WHITE (10900 4825);
DISPLAY INVISIBLE (10900 4825);
FORCEPROP 2 LAST CDS_LOCATION C1M24
J 0
(10900 4775);
DISPLAY 0.617021 (10900 4775);
PAINT AQUA (10900 4775);
DISPLAY INVISIBLE (10900 4775);
FORCEPROP 2 LAST CDS_LIB dev_discrete
J 0
(10850 4675);
PAINT ORANGE (10850 4675);
DISPLAY INVISIBLE (10850 4675);
FORCEPROP 2 LAST CDS_SEC 1
J 0
(10900 4825);
PAINT ORANGE (10900 4825);
DISPLAY INVISIBLE (10900 4825);
FORCEPROP 2 LAST SEC_TYPE 0402V
J 0
(10900 4875);
DISPLAY 1.021277 (10900 4875);
PAINT ORANGE (10900 4875);
DISPLAY INVISIBLE (10900 4875);
FORCEPROP 2 LAST SEC 1
J 0
(10900 4875);
DISPLAY 0.680851 (10900 4875);
PAINT MONO (10900 4875);
DISPLAY INVISIBLE (10900 4875);
FORCEPROP 0 LAST ROOM IO_SLOT
J 0
(10900 4875);
DISPLAY 1.021277 (10900 4875);
PAINT ORANGE (10900 4875);
DISPLAY INVISIBLE (10900 4875);
FORCEADD GND..1
(11650 3550);
FORCEPROP 3 LASTPIN (11650 3600) SIG_NAME GND\g
J 0
(11660 3610);
DISPLAY 0.659574 (11660 3610);
PAINT MONO (11660 3610);
DISPLAY INVISIBLE (11660 3610);
FORCEPROP 2 LAST CDS_LIB mstr_symbols
J 0
(11650 3550);
PAINT ORANGE (11650 3550);
DISPLAY INVISIBLE (11650 3550);
FORCEPROP 1 LAST SIZE 1B
J 0
(11725 3500);
DISPLAY 0.872340 (11725 3500);
PAINT AQUA (11725 3500);
DISPLAY INVISIBLE (11725 3500);
FORCEPROP 1 LAST BODY_TYPE PLUMBING
J 0
(11605 3507);
DISPLAY 0.340426 (11605 3507);
PAINT GREEN (11605 3507);
DISPLAY INVISIBLE (11605 3507);
FORCEPROP 1 LAST PATH I14
J 0
(11725 3550);
DISPLAY 0.872340 (11725 3550);
PAINT AQUA (11725 3550);
DISPLAY INVISIBLE (11725 3550);
FORCEPROP 1 LAST HDL_POWER GND
J 0
(11650 3700);
DISPLAY 0.872340 (11650 3700);
PAINT GREEN (11650 3700);
DISPLAY INVISIBLE (11650 3700);
FORCEPROP 1 LAST VOLTAGE 0
J 0
(11650 3550);
PAINT SKYBLUE (11650 3550);
DISPLAY INVISIBLE (11650 3550);
FORCEADD GND..1
(7525 700);
FORCEPROP 3 LASTPIN (7525 750) SIG_NAME GND\g
J 0
(7535 760);
DISPLAY 0.659574 (7535 760);
PAINT MONO (7535 760);
DISPLAY INVISIBLE (7535 760);
FORCEPROP 2 LAST CDS_LIB mstr_symbols
J 0
(7525 700);
PAINT ORANGE (7525 700);
DISPLAY INVISIBLE (7525 700);
FORCEPROP 1 LAST SIZE 1B
J 0
(7600 650);
DISPLAY 0.872340 (7600 650);
PAINT AQUA (7600 650);
DISPLAY INVISIBLE (7600 650);
FORCEPROP 1 LAST BODY_TYPE PLUMBING
J 0
(7480 657);
DISPLAY 0.340426 (7480 657);
PAINT GREEN (7480 657);
DISPLAY INVISIBLE (7480 657);
FORCEPROP 1 LAST PATH I192
J 0
(7600 700);
DISPLAY 0.872340 (7600 700);
PAINT AQUA (7600 700);
DISPLAY INVISIBLE (7600 700);
FORCEPROP 1 LAST HDL_POWER GND
J 0
(7525 850);
DISPLAY 0.872340 (7525 850);
PAINT GREEN (7525 850);
DISPLAY INVISIBLE (7525 850);
FORCEPROP 1 LAST VOLTAGE 0
J 0
(7525 700);
PAINT SKYBLUE (7525 700);
DISPLAY INVISIBLE (7525 700);
FORCEADD GND..1
(8975 725);
FORCEPROP 3 LASTPIN (8975 775) SIG_NAME GND\g
J 0
(8985 785);
DISPLAY 0.659574 (8985 785);
PAINT MONO (8985 785);
DISPLAY INVISIBLE (8985 785);
FORCEPROP 1 LAST SIZE 1B
J 0
(9050 675);
DISPLAY 0.872340 (9050 675);
PAINT AQUA (9050 675);
DISPLAY INVISIBLE (9050 675);
FORCEPROP 2 LAST CDS_LIB mstr_symbols
J 0
(8975 725);
PAINT ORANGE (8975 725);
DISPLAY INVISIBLE (8975 725);
FORCEPROP 1 LAST BODY_TYPE PLUMBING
J 0
(8930 682);
DISPLAY 0.340426 (8930 682);
PAINT GREEN (8930 682);
DISPLAY INVISIBLE (8930 682);
FORCEPROP 1 LAST PATH I193
J 0
(9050 725);
DISPLAY 0.872340 (9050 725);
PAINT AQUA (9050 725);
DISPLAY INVISIBLE (9050 725);
FORCEPROP 1 LAST HDL_POWER GND
J 0
(8975 875);
DISPLAY 0.872340 (8975 875);
PAINT GREEN (8975 875);
DISPLAY INVISIBLE (8975 875);
FORCEPROP 1 LAST VOLTAGE 0
J 0
(8975 725);
PAINT SKYBLUE (8975 725);
DISPLAY INVISIBLE (8975 725);
FORCEADD P3V3..1
(7050 4050);
FORCEPROP 3 LASTPIN (7050 4000) SIG_NAME P3V3\g
J 0
(7060 4010);
DISPLAY 0.659574 (7060 4010);
PAINT MONO (7060 4010);
DISPLAY INVISIBLE (7060 4010);
FORCEPROP 2 LAST CDS_LIB mstr_symbols
J 0
(7050 4050);
PAINT ORANGE (7050 4050);
DISPLAY INVISIBLE (7050 4050);
FORCEPROP 1 LAST SIZE 1B
J 0
(7095 4072);
DISPLAY 0.468085 (7095 4072);
PAINT GREEN (7095 4072);
DISPLAY INVISIBLE (7095 4072);
FORCEPROP 1 LAST BODY_TYPE PLUMBING
J 0
(7005 4007);
DISPLAY 0.468085 (7005 4007);
PAINT GREEN (7005 4007);
DISPLAY INVISIBLE (7005 4007);
FORCEPROP 1 LAST PATH I195
J 0
(7095 4052);
DISPLAY 0.340426 (7095 4052);
PAINT GREEN (7095 4052);
DISPLAY INVISIBLE (7095 4052);
FORCEPROP 1 LAST HDL_POWER P3V3
J 0
(6725 3925);
DISPLAY 1.170213 (6725 3925);
PAINT GREEN (6725 3925);
DISPLAY INVISIBLE (6725 3925);
FORCEPROP 1 LAST VOLTAGE +3.3
J 0
(7050 4050);
PAINT SKYBLUE (7050 4050);
DISPLAY INVISIBLE (7050 4050);
FORCEADD OFFPAGE..3
(9750 3100);
FORCEPROP 2 LAST $XR0 91 
J 0
(9964 3100);
DISPLAY 0.638298 (9964 3100);
PAINT MONO (9964 3100);
FORCEPROP 2 LAST $XR1 138 
J 0
(10054 3100);
DISPLAY 0.638298 (10054 3100);
PAINT MONO (10054 3100);
FORCEPROP 2 LAST $XR2 159 
J 0
(10174 3100);
DISPLAY 0.638298 (10174 3100);
PAINT MONO (10174 3100);
FORCEPROP 2 LAST $XR3 188 
J 0
(10294 3100);
DISPLAY 0.638298 (10294 3100);
PAINT MONO (10294 3100);
FORCEPROP 2 LAST PATH I217
J 2
(9575 3175);
DISPLAY 1.021277 (9575 3175);
PAINT ORANGE (9575 3175);
DISPLAY INVISIBLE (9575 3175);
FORCEPROP 1 LAST COMMENT_BODY TRUE
J 0
(9700 3000);
DISPLAY 0.872340 (9700 3000);
PAINT GREEN (9700 3000);
DISPLAY INVISIBLE (9700 3000);
FORCEPROP 1 LAST OFFPAGE TRUE
J 0
(10075 2975);
DISPLAY 0.872340 (10075 2975);
PAINT GREEN (10075 2975);
DISPLAY INVISIBLE (10075 2975);
FORCEPROP 2 LAST CDS_LIB mstr_standard
J 2
(9750 3100);
PAINT ORANGE (9750 3100);
DISPLAY INVISIBLE (9750 3100);
FORCEADD RES..1
(6000 3050);
FORCEPROP 1 LASTPIN (6100 3050) $PN 2
J 0
(6062 3062);
DISPLAY 0.617021 (6062 3062);
PAINT ORANGE (6062 3062);
FORCEPROP 1 LASTPIN (5900 3050) $PN 1
J 0
(5912 3062);
DISPLAY 0.617021 (5912 3062);
PAINT ORANGE (5912 3062);
FORCEPROP 1 LAST WATTAGE 1/16W
J 2
(5975 2900);
DISPLAY 0.617021 (5975 2900);
PAINT SKYBLUE (5975 2900);
FORCEPROP 1 LAST PACK_TYPE 0402
J 0
(6100 2975);
DISPLAY 0.617021 (6100 2975);
PAINT SKYBLUE (6100 2975);
FORCEPROP 1 LAST TOLERANCE 1%
J 0
(6000 2950);
DISPLAY 0.617021 (6000 2950);
PAINT SKYBLUE (6000 2950);
FORCEPROP 1 LAST VALUE 200.0
J 2
(5975 2950);
DISPLAY 0.617021 (5975 2950);
PAINT SKYBLUE (5975 2950);
FORCEPROP 1 LAST PART_NUMBER G21796-004
J 0
(5825 3000);
DISPLAY 0.617021 (5825 3000);
PAINT BLUE (5825 3000);
FORCEPROP 1 LAST LOCATION R1M14
J 0
(5950 3100);
DISPLAY 0.617021 (5950 3100);
PAINT AQUA (5950 3100);
FORCEPROP 1 LAST MATERIAL CHIP
J 0
(6000 2900);
DISPLAY 0.617021 (6000 2900);
PAINT SKYBLUE (6000 2900);
FORCEPROP 2 LAST SEC_TYPE 0402
J 0
(5950 3250);
DISPLAY 1.021277 (5950 3250);
PAINT ORANGE (5950 3250);
DISPLAY INVISIBLE (5950 3250);
FORCEPROP 2 LAST CDS_LIB mstr_discrete
J 0
(6000 3050);
PAINT MONO (6000 3050);
DISPLAY INVISIBLE (6000 3050);
FORCEPROP 2 LAST SEC 1
J 0
(5950 3250);
DISPLAY 0.680851 (5950 3250);
PAINT MONO (5950 3250);
DISPLAY INVISIBLE (5950 3250);
FORCEPROP 2 LAST CDS_LOCATION R1M14
J 0
(5950 3100);
DISPLAY 0.617021 (5950 3100);
PAINT AQUA (5950 3100);
DISPLAY INVISIBLE (5950 3100);
FORCEPROP 1 LAST PATH I220
J 0
(5950 3200);
DISPLAY 0.978723 (5950 3200);
PAINT WHITE (5950 3200);
DISPLAY INVISIBLE (5950 3200);
FORCEPROP 0 LAST ROOM IO_SLOT
J 0
(5950 3250);
DISPLAY 1.021277 (5950 3250);
PAINT ORANGE (5950 3250);
DISPLAY INVISIBLE (5950 3250);
FORCEADD OFFPAGE..1
(5150 3050);
FORCEPROP 2 LAST $XR0 191 
J 0
(4898 3050);
DISPLAY 0.638298 (4898 3050);
PAINT MONO (4898 3050);
FORCEPROP 2 LAST PATH I221
J 0
(5200 3125);
DISPLAY 1.021277 (5200 3125);
PAINT ORANGE (5200 3125);
DISPLAY INVISIBLE (5200 3125);
FORCEPROP 1 LAST COMMENT_BODY TRUE
J 0
(5275 2950);
DISPLAY 0.872340 (5275 2950);
PAINT GREEN (5275 2950);
DISPLAY INVISIBLE (5275 2950);
FORCEPROP 1 LAST OFFPAGE TRUE
J 0
(5475 2925);
DISPLAY 0.872340 (5475 2925);
PAINT GREEN (5475 2925);
DISPLAY INVISIBLE (5475 2925);
FORCEPROP 2 LAST CDS_LIB mstr_standard
J 0
(5150 3050);
PAINT ORANGE (5150 3050);
DISPLAY INVISIBLE (5150 3050);
FORCEADD RES..1
(6500 3850);
FORCEPROP 1 LASTPIN (6600 3850) $PN 2
J 0
(6562 3862);
DISPLAY 0.617021 (6562 3862);
PAINT ORANGE (6562 3862);
FORCEPROP 1 LASTPIN (6400 3850) $PN 1
J 0
(6412 3862);
DISPLAY 0.617021 (6412 3862);
PAINT ORANGE (6412 3862);
FORCEPROP 1 LAST WATTAGE 1/16W
J 2
(6475 3700);
DISPLAY 0.617021 (6475 3700);
PAINT SKYBLUE (6475 3700);
FORCEPROP 1 LAST MATERIAL CHIP
J 0
(6500 3700);
DISPLAY 0.617021 (6500 3700);
PAINT SKYBLUE (6500 3700);
FORCEPROP 1 LAST PACK_TYPE 0402
J 0
(6750 3700);
DISPLAY 0.617021 (6750 3700);
PAINT SKYBLUE (6750 3700);
FORCEPROP 1 LAST TOLERANCE 1%
J 0
(6500 3750);
DISPLAY 0.617021 (6500 3750);
PAINT SKYBLUE (6500 3750);
FORCEPROP 1 LAST VALUE 100.0
J 2
(6475 3750);
DISPLAY 0.617021 (6475 3750);
PAINT SKYBLUE (6475 3750);
FORCEPROP 1 LAST PART_NUMBER G21796-017
J 0
(6450 3950);
DISPLAY 0.617021 (6450 3950);
PAINT BLUE (6450 3950);
FORCEPROP 1 LAST LOCATION R9B7
J 0
(6450 3900);
DISPLAY 0.617021 (6450 3900);
PAINT AQUA (6450 3900);
FORCEPROP 2 LAST SEC_TYPE 0402
J 0
(6450 4050);
DISPLAY 1.021277 (6450 4050);
PAINT ORANGE (6450 4050);
DISPLAY INVISIBLE (6450 4050);
FORCEPROP 2 LAST CDS_LIB mstr_discrete
J 0
(6500 3850);
PAINT ORANGE (6500 3850);
DISPLAY INVISIBLE (6500 3850);
FORCEPROP 2 LAST SEC 1
J 0
(6450 4050);
DISPLAY 0.680851 (6450 4050);
PAINT MONO (6450 4050);
DISPLAY INVISIBLE (6450 4050);
FORCEPROP 2 LAST CDS_LOCATION R9B7
J 0
(6450 3900);
DISPLAY 0.617021 (6450 3900);
PAINT AQUA (6450 3900);
DISPLAY INVISIBLE (6450 3900);
FORCEPROP 1 LAST PATH I222
J 0
(6450 4000);
DISPLAY 0.978723 (6450 4000);
PAINT WHITE (6450 4000);
DISPLAY INVISIBLE (6450 4000);
FORCEPROP 0 LAST ROOM IO_SLOT
J 0
(6450 4050);
DISPLAY 1.021277 (6450 4050);
PAINT ORANGE (6450 4050);
DISPLAY INVISIBLE (6450 4050);
FORCEADD GND..1
(6325 3625);
FORCEPROP 3 LASTPIN (6325 3675) SIG_NAME GND\g
J 0
(6335 3685);
DISPLAY 0.659574 (6335 3685);
PAINT MONO (6335 3685);
DISPLAY INVISIBLE (6335 3685);
FORCEPROP 2 LAST CDS_LIB mstr_symbols
J 0
(6325 3625);
PAINT ORANGE (6325 3625);
DISPLAY INVISIBLE (6325 3625);
FORCEPROP 1 LAST SIZE 1B
J 0
(6400 3575);
DISPLAY 0.872340 (6400 3575);
PAINT AQUA (6400 3575);
DISPLAY INVISIBLE (6400 3575);
FORCEPROP 1 LAST BODY_TYPE PLUMBING
J 0
(6280 3582);
DISPLAY 0.340426 (6280 3582);
PAINT GREEN (6280 3582);
DISPLAY INVISIBLE (6280 3582);
FORCEPROP 1 LAST PATH I223
J 0
(6400 3625);
DISPLAY 0.872340 (6400 3625);
PAINT AQUA (6400 3625);
DISPLAY INVISIBLE (6400 3625);
FORCEPROP 1 LAST HDL_POWER GND
J 0
(6325 3775);
DISPLAY 0.872340 (6325 3775);
PAINT GREEN (6325 3775);
DISPLAY INVISIBLE (6325 3775);
FORCEPROP 1 LAST VOLTAGE 0
J 0
(6325 3625);
PAINT SKYBLUE (6325 3625);
DISPLAY INVISIBLE (6325 3625);
FORCEADD OFFPAGE..1
(6825 3150);
FORCEPROP 2 LAST $XR0 101 
J 0
(6543 3150);
DISPLAY 0.638298 (6543 3150);
PAINT MONO (6543 3150);
FORCEPROP 2 LAST PATH I227
J 0
(6875 3225);
DISPLAY 1.021277 (6875 3225);
PAINT ORANGE (6875 3225);
DISPLAY INVISIBLE (6875 3225);
FORCEPROP 1 LAST COMMENT_BODY TRUE
J 0
(6950 3050);
DISPLAY 0.872340 (6950 3050);
PAINT GREEN (6950 3050);
DISPLAY INVISIBLE (6950 3050);
FORCEPROP 1 LAST OFFPAGE TRUE
J 0
(7150 3025);
DISPLAY 0.872340 (7150 3025);
PAINT GREEN (7150 3025);
DISPLAY INVISIBLE (7150 3025);
FORCEPROP 2 LAST CDS_LIB mstr_standard
J 0
(6825 3150);
PAINT ORANGE (6825 3150);
DISPLAY INVISIBLE (6825 3150);
FORCEADD OFFPAGE..1
(6825 3100);
FORCEPROP 2 LAST $XR0 147 
J 0
(6543 3100);
DISPLAY 0.638298 (6543 3100);
PAINT MONO (6543 3100);
FORCEPROP 2 LAST $XR1 151 
J 0
(6543 3100);
DISPLAY 0.638298 (6543 3100);
PAINT MONO (6543 3100);
FORCEPROP 2 LAST PATH I228
J 0
(6875 3175);
DISPLAY 1.021277 (6875 3175);
PAINT ORANGE (6875 3175);
DISPLAY INVISIBLE (6875 3175);
FORCEPROP 1 LAST COMMENT_BODY TRUE
J 0
(6950 3000);
DISPLAY 0.872340 (6950 3000);
PAINT GREEN (6950 3000);
DISPLAY INVISIBLE (6950 3000);
FORCEPROP 1 LAST OFFPAGE TRUE
J 0
(7150 2975);
DISPLAY 0.872340 (7150 2975);
PAINT GREEN (7150 2975);
DISPLAY INVISIBLE (7150 2975);
FORCEPROP 2 LAST CDS_LIB mstr_standard
J 0
(6825 3100);
PAINT ORANGE (6825 3100);
DISPLAY INVISIBLE (6825 3100);
FORCEADD OFFPAGE..1
(6825 3000);
FORCEPROP 2 LAST $XR0 159 
J 0
(6543 3000);
DISPLAY 0.638298 (6543 3000);
PAINT MONO (6543 3000);
FORCEPROP 2 LAST PATH I229
J 0
(6875 3075);
DISPLAY 1.021277 (6875 3075);
PAINT ORANGE (6875 3075);
DISPLAY INVISIBLE (6875 3075);
FORCEPROP 1 LAST COMMENT_BODY TRUE
J 0
(6950 2900);
DISPLAY 0.872340 (6950 2900);
PAINT GREEN (6950 2900);
DISPLAY INVISIBLE (6950 2900);
FORCEPROP 1 LAST OFFPAGE TRUE
J 0
(7150 2875);
DISPLAY 0.872340 (7150 2875);
PAINT GREEN (7150 2875);
DISPLAY INVISIBLE (7150 2875);
FORCEPROP 2 LAST CDS_LIB mstr_standard
J 0
(6825 3000);
PAINT ORANGE (6825 3000);
DISPLAY INVISIBLE (6825 3000);
FORCEADD OFFPAGE..1
(6825 2600);
FORCEPROP 2 LAST $XR0 114 
J 0
(6543 2600);
DISPLAY 0.638298 (6543 2600);
PAINT MONO (6543 2600);
FORCEPROP 2 LAST PATH I233
J 0
(6875 2675);
DISPLAY 1.021277 (6875 2675);
PAINT ORANGE (6875 2675);
DISPLAY INVISIBLE (6875 2675);
FORCEPROP 1 LAST COMMENT_BODY TRUE
J 0
(6950 2500);
DISPLAY 0.872340 (6950 2500);
PAINT GREEN (6950 2500);
DISPLAY INVISIBLE (6950 2500);
FORCEPROP 1 LAST OFFPAGE TRUE
J 0
(7150 2475);
DISPLAY 0.872340 (7150 2475);
PAINT GREEN (7150 2475);
DISPLAY INVISIBLE (7150 2475);
FORCEPROP 2 LAST CDS_LIB mstr_standard
J 0
(6825 2600);
PAINT ORANGE (6825 2600);
DISPLAY INVISIBLE (6825 2600);
FORCEADD OFFPAGE..1
(6825 2550);
FORCEPROP 2 LAST $XR0 114 
J 0
(6543 2550);
DISPLAY 0.638298 (6543 2550);
PAINT MONO (6543 2550);
FORCEPROP 2 LAST PATH I234
J 0
(6875 2625);
DISPLAY 1.021277 (6875 2625);
PAINT ORANGE (6875 2625);
DISPLAY INVISIBLE (6875 2625);
FORCEPROP 1 LAST COMMENT_BODY TRUE
J 0
(6950 2450);
DISPLAY 0.872340 (6950 2450);
PAINT GREEN (6950 2450);
DISPLAY INVISIBLE (6950 2450);
FORCEPROP 1 LAST OFFPAGE TRUE
J 0
(7150 2425);
DISPLAY 0.872340 (7150 2425);
PAINT GREEN (7150 2425);
DISPLAY INVISIBLE (7150 2425);
FORCEPROP 2 LAST CDS_LIB mstr_standard
J 0
(6825 2550);
PAINT ORANGE (6825 2550);
DISPLAY INVISIBLE (6825 2550);
FORCEADD P3V3..1
(8850 4050);
FORCEPROP 3 LASTPIN (8850 4000) SIG_NAME P3V3\g
J 0
(8860 4010);
DISPLAY 0.659574 (8860 4010);
PAINT MONO (8860 4010);
DISPLAY INVISIBLE (8860 4010);
FORCEPROP 2 LAST CDS_LIB mstr_symbols
J 0
(8850 4050);
PAINT ORANGE (8850 4050);
DISPLAY INVISIBLE (8850 4050);
FORCEPROP 1 LAST SIZE 1B
J 0
(8895 4072);
DISPLAY 0.468085 (8895 4072);
PAINT GREEN (8895 4072);
DISPLAY INVISIBLE (8895 4072);
FORCEPROP 1 LAST BODY_TYPE PLUMBING
J 0
(8805 4007);
DISPLAY 0.468085 (8805 4007);
PAINT GREEN (8805 4007);
DISPLAY INVISIBLE (8805 4007);
FORCEPROP 1 LAST PATH I247
J 0
(8895 4052);
DISPLAY 0.340426 (8895 4052);
PAINT GREEN (8895 4052);
DISPLAY INVISIBLE (8895 4052);
FORCEPROP 1 LAST HDL_POWER P3V3
J 0
(8525 3925);
DISPLAY 1.170213 (8525 3925);
PAINT GREEN (8525 3925);
DISPLAY INVISIBLE (8525 3925);
FORCEPROP 1 LAST VOLTAGE +3.3
J 0
(8850 4050);
PAINT SKYBLUE (8850 4050);
DISPLAY INVISIBLE (8850 4050);
FORCEADD OFFPAGE..3
R 2
(6825 2950);
FORCEPROP 2 LAST $XR0 159 
J 0
(6545 2950);
DISPLAY 0.638298 (6545 2950);
PAINT MONO (6545 2950);
FORCEPROP 2 LAST PATH I249
J 2
(6625 3025);
DISPLAY 1.021277 (6625 3025);
PAINT ORANGE (6625 3025);
DISPLAY INVISIBLE (6625 3025);
FORCEPROP 1 LAST COMMENT_BODY TRUE
J 2
(6875 2850);
DISPLAY 0.872340 (6875 2850);
PAINT GREEN (6875 2850);
DISPLAY INVISIBLE (6875 2850);
FORCEPROP 1 LAST OFFPAGE TRUE
J 2
(6500 2825);
DISPLAY 0.872340 (6500 2825);
PAINT GREEN (6500 2825);
DISPLAY INVISIBLE (6500 2825);
FORCEPROP 2 LAST CDS_LIB mstr_standard
J 2
(6825 2950);
PAINT ORANGE (6825 2950);
DISPLAY INVISIBLE (6825 2950);
FORCEADD OFFPAGE..1
R 2
(9750 3150);
FORCEPROP 2 LAST $XR0 138 
J 0
(9936 3150);
DISPLAY 0.638298 (9936 3150);
PAINT MONO (9936 3150);
FORCEPROP 2 LAST $XR1 159 
J 0
(10056 3150);
DISPLAY 0.638298 (10056 3150);
PAINT MONO (10056 3150);
FORCEPROP 2 LAST $XR2 91 
J 0
(10176 3150);
DISPLAY 0.638298 (10176 3150);
PAINT MONO (10176 3150);
FORCEPROP 2 LAST $XR3 188 
J 0
(10266 3150);
DISPLAY 0.638298 (10266 3150);
PAINT MONO (10266 3150);
FORCEPROP 2 LAST PATH I250
J 0
(9925 3225);
DISPLAY 1.021277 (9925 3225);
PAINT ORANGE (9925 3225);
DISPLAY INVISIBLE (9925 3225);
FORCEPROP 1 LAST COMMENT_BODY TRUE
J 2
(9625 3050);
DISPLAY 0.872340 (9625 3050);
PAINT GREEN (9625 3050);
DISPLAY INVISIBLE (9625 3050);
FORCEPROP 1 LAST OFFPAGE TRUE
J 2
(9425 3025);
DISPLAY 0.872340 (9425 3025);
PAINT GREEN (9425 3025);
DISPLAY INVISIBLE (9425 3025);
FORCEPROP 2 LAST CDS_LIB mstr_standard
J 0
(9750 3150);
PAINT ORANGE (9750 3150);
DISPLAY INVISIBLE (9750 3150);
FORCEADD OFFPAGE..2
(9750 3200);
FORCEPROP 2 LAST $XR0 157 
J 0
(9939 3200);
DISPLAY 0.638298 (9939 3200);
PAINT MONO (9939 3200);
FORCEPROP 2 LAST $XR1 119 
J 0
(10059 3200);
DISPLAY 0.638298 (10059 3200);
PAINT MONO (10059 3200);
FORCEPROP 2 LAST $XR2 146 
J 0
(10179 3200);
DISPLAY 0.638298 (10179 3200);
PAINT MONO (10179 3200);
FORCEPROP 2 LAST PATH I251
J 2
(9575 3275);
DISPLAY 1.021277 (9575 3275);
PAINT ORANGE (9575 3275);
DISPLAY INVISIBLE (9575 3275);
FORCEPROP 1 LAST COMMENT_BODY TRUE
J 0
(9705 3105);
DISPLAY 0.872340 (9705 3105);
PAINT GREEN (9705 3105);
DISPLAY INVISIBLE (9705 3105);
FORCEPROP 1 LAST OFFPAGE TRUE
J 0
(10075 3075);
DISPLAY 0.872340 (10075 3075);
PAINT GREEN (10075 3075);
DISPLAY INVISIBLE (10075 3075);
FORCEPROP 2 LAST CDS_LIB mstr_standard
J 2
(9750 3200);
PAINT ORANGE (9750 3200);
DISPLAY INVISIBLE (9750 3200);
FORCEADD OFFPAGE..2
(9750 3050);
FORCEPROP 2 LAST $XR0 142 
J 0
(9969 3050);
DISPLAY 0.638298 (9969 3050);
PAINT MONO (9969 3050);
FORCEPROP 2 LAST PATH I252
J 0
(9925 3125);
DISPLAY 1.021277 (9925 3125);
PAINT ORANGE (9925 3125);
DISPLAY INVISIBLE (9925 3125);
FORCEPROP 1 LAST COMMENT_BODY TRUE
J 0
(9705 2955);
DISPLAY 0.872340 (9705 2955);
PAINT GREEN (9705 2955);
DISPLAY INVISIBLE (9705 2955);
FORCEPROP 1 LAST OFFPAGE TRUE
J 0
(10075 2925);
DISPLAY 0.872340 (10075 2925);
PAINT GREEN (10075 2925);
DISPLAY INVISIBLE (10075 2925);
FORCEPROP 2 LAST CDS_LIB mstr_standard
J 0
(9750 3050);
PAINT ORANGE (9750 3050);
DISPLAY INVISIBLE (9750 3050);
FORCEADD OFFPAGE..1
R 2
(9750 2900);
FORCEPROP 2 LAST $XR0 147 
J 0
(9936 2900);
DISPLAY 0.638298 (9936 2900);
PAINT MONO (9936 2900);
FORCEPROP 2 LAST PATH I254
J 0
(9925 2975);
DISPLAY 1.021277 (9925 2975);
PAINT ORANGE (9925 2975);
DISPLAY INVISIBLE (9925 2975);
FORCEPROP 1 LAST COMMENT_BODY TRUE
J 2
(9625 2800);
DISPLAY 0.872340 (9625 2800);
PAINT GREEN (9625 2800);
DISPLAY INVISIBLE (9625 2800);
FORCEPROP 1 LAST OFFPAGE TRUE
J 2
(9425 2775);
DISPLAY 0.872340 (9425 2775);
PAINT GREEN (9425 2775);
DISPLAY INVISIBLE (9425 2775);
FORCEPROP 2 LAST CDS_LIB mstr_standard
J 0
(9750 2900);
PAINT ORANGE (9750 2900);
DISPLAY INVISIBLE (9750 2900);
FORCEADD OFFPAGE..1
R 2
(9750 2850);
FORCEPROP 2 LAST $XR0 147 
J 0
(9936 2850);
DISPLAY 0.638298 (9936 2850);
PAINT MONO (9936 2850);
FORCEPROP 2 LAST PATH I255
J 0
(9925 2925);
DISPLAY 1.021277 (9925 2925);
PAINT ORANGE (9925 2925);
DISPLAY INVISIBLE (9925 2925);
FORCEPROP 1 LAST COMMENT_BODY TRUE
J 2
(9625 2750);
DISPLAY 0.872340 (9625 2750);
PAINT GREEN (9625 2750);
DISPLAY INVISIBLE (9625 2750);
FORCEPROP 1 LAST OFFPAGE TRUE
J 2
(9425 2725);
DISPLAY 0.872340 (9425 2725);
PAINT GREEN (9425 2725);
DISPLAY INVISIBLE (9425 2725);
FORCEPROP 2 LAST CDS_LIB mstr_standard
J 0
(9750 2850);
PAINT ORANGE (9750 2850);
DISPLAY INVISIBLE (9750 2850);
FORCEADD OFFPAGE..1
R 2
(9750 2700);
FORCEPROP 2 LAST $XR0 114 
J 0
(9936 2700);
DISPLAY 0.638298 (9936 2700);
PAINT MONO (9936 2700);
FORCEPROP 2 LAST PATH I256
J 0
(9925 2775);
DISPLAY 1.021277 (9925 2775);
PAINT ORANGE (9925 2775);
DISPLAY INVISIBLE (9925 2775);
FORCEPROP 1 LAST COMMENT_BODY TRUE
J 2
(9625 2600);
DISPLAY 0.872340 (9625 2600);
PAINT GREEN (9625 2600);
DISPLAY INVISIBLE (9625 2600);
FORCEPROP 1 LAST OFFPAGE TRUE
J 2
(9425 2575);
DISPLAY 0.872340 (9425 2575);
PAINT GREEN (9425 2575);
DISPLAY INVISIBLE (9425 2575);
FORCEPROP 2 LAST CDS_LIB mstr_standard
J 0
(9750 2700);
PAINT ORANGE (9750 2700);
DISPLAY INVISIBLE (9750 2700);
FORCEADD OFFPAGE..1
R 2
(9750 2650);
FORCEPROP 2 LAST $XR0 114 
J 0
(9936 2650);
DISPLAY 0.638298 (9936 2650);
PAINT MONO (9936 2650);
FORCEPROP 2 LAST PATH I257
J 0
(9925 2725);
DISPLAY 1.021277 (9925 2725);
PAINT ORANGE (9925 2725);
DISPLAY INVISIBLE (9925 2725);
FORCEPROP 1 LAST COMMENT_BODY TRUE
J 2
(9625 2550);
DISPLAY 0.872340 (9625 2550);
PAINT GREEN (9625 2550);
DISPLAY INVISIBLE (9625 2550);
FORCEPROP 1 LAST OFFPAGE TRUE
J 2
(9425 2525);
DISPLAY 0.872340 (9425 2525);
PAINT GREEN (9425 2525);
DISPLAY INVISIBLE (9425 2525);
FORCEPROP 2 LAST CDS_LIB mstr_standard
J 0
(9750 2650);
PAINT ORANGE (9750 2650);
DISPLAY INVISIBLE (9750 2650);
FORCEADD OFFPAGE..2
(9825 900);
FORCEPROP 2 LAST $XR2 119 
J 0
(10134 900);
DISPLAY 0.638298 (10134 900);
PAINT MONO (10134 900);
FORCEPROP 2 LAST $XR0 133 
J 0
(10014 900);
DISPLAY 0.638298 (10014 900);
PAINT MONO (10014 900);
FORCEPROP 2 LAST $XR1 145 
J 0
(10134 900);
DISPLAY 0.638298 (10134 900);
PAINT MONO (10134 900);
FORCEPROP 2 LAST PATH I267
J 0
(10000 975);
DISPLAY 1.021277 (10000 975);
PAINT ORANGE (10000 975);
DISPLAY INVISIBLE (10000 975);
FORCEPROP 1 LAST COMMENT_BODY TRUE
J 0
(9780 805);
DISPLAY 0.872340 (9780 805);
PAINT GREEN (9780 805);
DISPLAY INVISIBLE (9780 805);
FORCEPROP 1 LAST OFFPAGE TRUE
J 0
(10150 775);
DISPLAY 0.872340 (10150 775);
PAINT GREEN (10150 775);
DISPLAY INVISIBLE (10150 775);
FORCEPROP 2 LAST CDS_LIB mstr_standard
J 0
(9825 900);
PAINT ORANGE (9825 900);
DISPLAY INVISIBLE (9825 900);
FORCEADD P3V3..1
(10450 4950);
FORCEPROP 3 LASTPIN (10450 4900) SIG_NAME P3V3\g
J 0
(10460 4910);
DISPLAY 0.659574 (10460 4910);
PAINT MONO (10460 4910);
DISPLAY INVISIBLE (10460 4910);
FORCEPROP 1 LAST SIZE 1B
J 0
(10495 4972);
DISPLAY 0.468085 (10495 4972);
PAINT GREEN (10495 4972);
DISPLAY INVISIBLE (10495 4972);
FORCEPROP 2 LAST CDS_LIB mstr_symbols
J 0
(10450 4950);
PAINT ORANGE (10450 4950);
DISPLAY INVISIBLE (10450 4950);
FORCEPROP 1 LAST BODY_TYPE PLUMBING
J 0
(10405 4907);
DISPLAY 0.468085 (10405 4907);
PAINT GREEN (10405 4907);
DISPLAY INVISIBLE (10405 4907);
FORCEPROP 1 LAST PATH I268
J 0
(10495 4952);
DISPLAY 0.340426 (10495 4952);
PAINT GREEN (10495 4952);
DISPLAY INVISIBLE (10495 4952);
FORCEPROP 1 LAST HDL_POWER P3V3
J 0
(10125 4825);
DISPLAY 1.170213 (10125 4825);
PAINT GREEN (10125 4825);
DISPLAY INVISIBLE (10125 4825);
FORCEPROP 1 LAST VOLTAGE +3.3
J 0
(10450 4950);
PAINT SKYBLUE (10450 4950);
DISPLAY INVISIBLE (10450 4950);
FORCEADD GND..1
(11650 4275);
FORCEPROP 3 LASTPIN (11650 4325) SIG_NAME GND\g
J 0
(11660 4335);
DISPLAY 0.659574 (11660 4335);
PAINT MONO (11660 4335);
DISPLAY INVISIBLE (11660 4335);
FORCEPROP 2 LAST CDS_LIB mstr_symbols
J 0
(11650 4275);
PAINT ORANGE (11650 4275);
DISPLAY INVISIBLE (11650 4275);
FORCEPROP 1 LAST PATH I269
J 0
(11725 4275);
DISPLAY 0.872340 (11725 4275);
PAINT AQUA (11725 4275);
DISPLAY INVISIBLE (11725 4275);
FORCEPROP 1 LAST BODY_TYPE PLUMBING
J 0
(11605 4232);
DISPLAY 0.340426 (11605 4232);
PAINT GREEN (11605 4232);
DISPLAY INVISIBLE (11605 4232);
FORCEPROP 1 LAST SIZE 1B
J 0
(11725 4225);
DISPLAY 0.872340 (11725 4225);
PAINT AQUA (11725 4225);
DISPLAY INVISIBLE (11725 4225);
FORCEPROP 1 LAST HDL_POWER GND
J 0
(11650 4425);
DISPLAY 0.872340 (11650 4425);
PAINT GREEN (11650 4425);
DISPLAY INVISIBLE (11650 4425);
FORCEPROP 1 LAST VOLTAGE 0
J 0
(11650 4275);
PAINT SKYBLUE (11650 4275);
DISPLAY INVISIBLE (11650 4275);
FORCEADD CAP_A..1
(11650 4675);
FORCEPROP 1 LAST MATERIAL X7R
J 0
(11700 4575);
DISPLAY 0.617021 (11700 4575);
PAINT SKYBLUE (11700 4575);
FORCEPROP 1 LAST VOLTAGE 16V
J 0
(11700 4675);
DISPLAY 0.617021 (11700 4675);
PAINT SKYBLUE (11700 4675);
FORCEPROP 1 LAST PACK_TYPE 0402V
J 0
(11700 4475);
DISPLAY 0.617021 (11700 4475);
PAINT SKYBLUE (11700 4475);
FORCEPROP 1 LAST TOLERANCE 10%
J 0
(11700 4625);
DISPLAY 0.617021 (11700 4625);
PAINT SKYBLUE (11700 4625);
FORCEPROP 1 LAST VALUE 0.1UF
J 0
(11700 4725);
DISPLAY 0.617021 (11700 4725);
PAINT SKYBLUE (11700 4725);
FORCEPROP 1 LAST PART_NUMBER A36096-030
J 0
(11700 4525);
DISPLAY 0.617021 (11700 4525);
PAINT BLUE (11700 4525);
FORCEPROP 1 LAST LOCATION C1M20
J 0
(11700 4775);
DISPLAY 0.617021 (11700 4775);
PAINT AQUA (11700 4775);
FORCEPROP 2 LAST CDS_SEC 1
J 0
(11700 4875);
DISPLAY 1.021277 (11700 4875);
PAINT ORANGE (11700 4875);
DISPLAY INVISIBLE (11700 4875);
FORCEPROP 2 LAST CDS_LIB dev_discrete
J 0
(11650 4675);
PAINT ORANGE (11650 4675);
DISPLAY INVISIBLE (11650 4675);
FORCEPROP 2 LAST CDS_LOCATION C1M20
J 0
(11700 4775);
DISPLAY 0.617021 (11700 4775);
PAINT AQUA (11700 4775);
DISPLAY INVISIBLE (11700 4775);
FORCEPROP 2 LAST $SEC 1
J 0
(11700 4875);
DISPLAY 0.680851 (11700 4875);
PAINT MONO (11700 4875);
DISPLAY INVISIBLE (11700 4875);
FORCEPROP 1 LAST PATH I270
J 0
(11700 4825);
DISPLAY 0.978723 (11700 4825);
PAINT WHITE (11700 4825);
DISPLAY INVISIBLE (11700 4825);
FORCEPROP 0 LAST ROOM IO_SLOT
J 0
(11700 4875);
DISPLAY 1.021277 (11700 4875);
PAINT ORANGE (11700 4875);
DISPLAY INVISIBLE (11700 4875);
FORCEPROP 1 LASTPIN (11650 4575) $PN 2
J 0
(11660 4555);
DISPLAY 0.787234 (11660 4555);
PAINT ORANGE (11660 4555);
DISPLAY INVISIBLE (11660 4555);
FORCEPROP 1 LASTPIN (11650 4775) $PN 1
J 0
(11660 4755);
DISPLAY 0.787234 (11660 4755);
PAINT ORANGE (11660 4755);
DISPLAY INVISIBLE (11660 4755);
FORCEADD P3V3_STBY..1
(7375 4025);
FORCEPROP 3 LASTPIN (7375 3975) SIG_NAME P3V3_STBY\g
J 0
(7385 3985);
DISPLAY 0.659574 (7385 3985);
PAINT MONO (7385 3985);
DISPLAY INVISIBLE (7385 3985);
FORCEPROP 2 LAST CDS_LIB mstr_symbols
J 0
(7375 4025);
PAINT ORANGE (7375 4025);
DISPLAY INVISIBLE (7375 4025);
FORCEPROP 1 LAST SIZE 1B
J 0
(7420 4047);
DISPLAY 0.340426 (7420 4047);
PAINT GREEN (7420 4047);
DISPLAY INVISIBLE (7420 4047);
FORCEPROP 1 LAST BODY_TYPE PLUMBING
J 0
(7330 3982);
DISPLAY 0.340426 (7330 3982);
PAINT GREEN (7330 3982);
DISPLAY INVISIBLE (7330 3982);
FORCEPROP 1 LAST PATH I274
J 0
(7420 4027);
DISPLAY 0.340426 (7420 4027);
PAINT GREEN (7420 4027);
DISPLAY INVISIBLE (7420 4027);
FORCEPROP 1 LAST HDL_POWER P3V3_STBY
J 0
(7075 3900);
DISPLAY 0.872340 (7075 3900);
PAINT ORANGE (7075 3900);
DISPLAY INVISIBLE (7075 3900);
FORCEPROP 1 LAST VOLTAGE 3.3V
J 0
(7330 3982);
DISPLAY 0.340426 (7330 3982);
PAINT SKYBLUE (7330 3982);
DISPLAY INVISIBLE (7330 3982);
FORCEADD P3V3_STBY..1
(8725 4200);
FORCEPROP 3 LASTPIN (8725 4150) SIG_NAME P3V3_STBY\g
J 0
(8735 4160);
DISPLAY 0.659574 (8735 4160);
PAINT MONO (8735 4160);
DISPLAY INVISIBLE (8735 4160);
FORCEPROP 1 LAST SIZE 1B
J 0
(8770 4222);
DISPLAY 0.340426 (8770 4222);
PAINT GREEN (8770 4222);
DISPLAY INVISIBLE (8770 4222);
FORCEPROP 2 LAST CDS_LIB mstr_symbols
J 0
(8725 4200);
PAINT ORANGE (8725 4200);
DISPLAY INVISIBLE (8725 4200);
FORCEPROP 1 LAST BODY_TYPE PLUMBING
J 0
(8680 4157);
DISPLAY 0.340426 (8680 4157);
PAINT GREEN (8680 4157);
DISPLAY INVISIBLE (8680 4157);
FORCEPROP 1 LAST PATH I275
J 0
(8770 4202);
DISPLAY 0.340426 (8770 4202);
PAINT GREEN (8770 4202);
DISPLAY INVISIBLE (8770 4202);
FORCEPROP 1 LAST HDL_POWER P3V3_STBY
J 0
(8425 4075);
DISPLAY 0.872340 (8425 4075);
PAINT ORANGE (8425 4075);
DISPLAY INVISIBLE (8425 4075);
FORCEPROP 1 LAST VOLTAGE 3.3V
J 0
(8680 4157);
DISPLAY 0.340426 (8680 4157);
PAINT SKYBLUE (8680 4157);
DISPLAY INVISIBLE (8680 4157);
FORCEADD P5V_STBY..1
(7650 4050);
FORCEPROP 3 LASTPIN (7650 4000) SIG_NAME P5V_STBY\g
J 0
(7660 4010);
DISPLAY 0.659574 (7660 4010);
PAINT MONO (7660 4010);
DISPLAY INVISIBLE (7660 4010);
FORCEPROP 2 LAST CDS_LIB mstr_symbols
J 0
(7650 4050);
PAINT ORANGE (7650 4050);
DISPLAY INVISIBLE (7650 4050);
FORCEPROP 1 LAST PATH I276
J 0
(7695 4052);
DISPLAY 0.340426 (7695 4052);
PAINT GREEN (7695 4052);
DISPLAY INVISIBLE (7695 4052);
FORCEPROP 1 LAST BODY_TYPE PLUMBING
J 0
(7605 4007);
DISPLAY 0.340426 (7605 4007);
PAINT GREEN (7605 4007);
DISPLAY INVISIBLE (7605 4007);
FORCEPROP 1 LAST SIZE 1B
J 0
(7695 4072);
DISPLAY 0.340426 (7695 4072);
PAINT GREEN (7695 4072);
DISPLAY INVISIBLE (7695 4072);
FORCEPROP 1 LAST HDL_POWER P5V_STBY
J 0
(7350 3925);
DISPLAY 0.872340 (7350 3925);
PAINT ORANGE (7350 3925);
DISPLAY INVISIBLE (7350 3925);
FORCEPROP 1 LAST VOLTAGE 5.0V
J 0
(7605 4007);
DISPLAY 0.340426 (7605 4007);
PAINT SKYBLUE (7605 4007);
DISPLAY INVISIBLE (7605 4007);
FORCEADD P12V_STBY..1
(9200 4225);
FORCEPROP 3 LASTPIN (9200 4175) SIG_NAME P12V_STBY\g
J 0
(9210 4185);
DISPLAY 0.659574 (9210 4185);
PAINT MONO (9210 4185);
DISPLAY INVISIBLE (9210 4185);
FORCEPROP 1 LAST VOLTAGE 12.0V
J 0
(9155 4182);
DISPLAY 0.340426 (9155 4182);
PAINT SKYBLUE (9155 4182);
DISPLAY INVISIBLE (9155 4182);
FORCEPROP 1 LAST HDL_POWER P12V_STBY
J 0
(8900 4100);
DISPLAY 0.872340 (8900 4100);
PAINT ORANGE (8900 4100);
DISPLAY INVISIBLE (8900 4100);
FORCEPROP 1 LAST PATH I278
J 0
(9245 4227);
DISPLAY 0.340426 (9245 4227);
PAINT GREEN (9245 4227);
DISPLAY INVISIBLE (9245 4227);
FORCEPROP 1 LAST BODY_TYPE PLUMBING
J 0
(9155 4182);
DISPLAY 0.340426 (9155 4182);
PAINT GREEN (9155 4182);
DISPLAY INVISIBLE (9155 4182);
FORCEPROP 2 LAST CDS_LIB mstr_symbols
J 0
(9200 4225);
PAINT ORANGE (9200 4225);
DISPLAY INVISIBLE (9200 4225);
FORCEPROP 1 LAST SIZE 1B
J 0
(9245 4247);
DISPLAY 0.340426 (9245 4247);
PAINT GREEN (9245 4247);
DISPLAY INVISIBLE (9245 4247);
FORCEADD P12V_STBY..1
(10450 4225);
FORCEPROP 3 LASTPIN (10450 4175) SIG_NAME P12V_STBY\g
J 0
(10460 4185);
DISPLAY 0.659574 (10460 4185);
PAINT MONO (10460 4185);
DISPLAY INVISIBLE (10460 4185);
FORCEPROP 1 LAST SIZE 1B
J 0
(10495 4247);
DISPLAY 0.340426 (10495 4247);
PAINT GREEN (10495 4247);
DISPLAY INVISIBLE (10495 4247);
FORCEPROP 2 LAST CDS_LIB mstr_symbols
J 0
(10450 4225);
PAINT ORANGE (10450 4225);
DISPLAY INVISIBLE (10450 4225);
FORCEPROP 1 LAST BODY_TYPE PLUMBING
J 0
(10405 4182);
DISPLAY 0.340426 (10405 4182);
PAINT GREEN (10405 4182);
DISPLAY INVISIBLE (10405 4182);
FORCEPROP 1 LAST PATH I279
J 0
(10495 4227);
DISPLAY 0.340426 (10495 4227);
PAINT GREEN (10495 4227);
DISPLAY INVISIBLE (10495 4227);
FORCEPROP 1 LAST HDL_POWER P12V_STBY
J 0
(10150 4100);
DISPLAY 0.872340 (10150 4100);
PAINT ORANGE (10150 4100);
DISPLAY INVISIBLE (10150 4100);
FORCEPROP 1 LAST VOLTAGE 12.0V
J 0
(10405 4182);
DISPLAY 0.340426 (10405 4182);
PAINT SKYBLUE (10405 4182);
DISPLAY INVISIBLE (10405 4182);
FORCEADD P3V3_STBY..1
(11250 4950);
FORCEPROP 3 LASTPIN (11250 4900) SIG_NAME P3V3_STBY\g
J 0
(11260 4910);
DISPLAY 0.659574 (11260 4910);
PAINT MONO (11260 4910);
DISPLAY INVISIBLE (11260 4910);
FORCEPROP 1 LAST SIZE 1B
J 0
(11295 4972);
DISPLAY 0.340426 (11295 4972);
PAINT GREEN (11295 4972);
DISPLAY INVISIBLE (11295 4972);
FORCEPROP 2 LAST CDS_LIB mstr_symbols
J 0
(11250 4950);
PAINT ORANGE (11250 4950);
DISPLAY INVISIBLE (11250 4950);
FORCEPROP 1 LAST BODY_TYPE PLUMBING
J 0
(11205 4907);
DISPLAY 0.340426 (11205 4907);
PAINT GREEN (11205 4907);
DISPLAY INVISIBLE (11205 4907);
FORCEPROP 1 LAST PATH I296
J 0
(11295 4952);
DISPLAY 0.340426 (11295 4952);
PAINT GREEN (11295 4952);
DISPLAY INVISIBLE (11295 4952);
FORCEPROP 1 LAST HDL_POWER P3V3_STBY
J 0
(10950 4825);
DISPLAY 0.872340 (10950 4825);
PAINT ORANGE (10950 4825);
DISPLAY INVISIBLE (10950 4825);
FORCEPROP 1 LAST VOLTAGE 3.3V
J 0
(11205 4907);
DISPLAY 0.340426 (11205 4907);
PAINT SKYBLUE (11205 4907);
DISPLAY INVISIBLE (11205 4907);
FORCEADD TAP..1
R 2
(6250 1750);
FORCEPROP 3 LASTPIN (6300 1750) SIG_NAME P3E_CPU0_PE3_OCP_RXN<12>
J 0
(6310 1760);
DISPLAY 0.659574 (6310 1760);
PAINT MONO (6310 1760);
DISPLAY INVISIBLE (6310 1760);
FORCEPROP 1 LASTPIN (6300 1750) BN 12
J 2
(6312 1758);
DISPLAY 0.617021 (6312 1758);
PAINT GREEN (6312 1758);
FORCEPROP 2 LAST CDS_LIB mstr_standard
J 0
(6250 1750);
PAINT ORANGE (6250 1750);
DISPLAY INVISIBLE (6250 1750);
FORCEPROP 1 LAST BODY_TYPE PLUMBING
J 2
(6250 1800);
DISPLAY 0.872340 (6250 1800);
PAINT GREEN (6250 1800);
DISPLAY INVISIBLE (6250 1800);
FORCEPROP 1 LAST HDL_TAP TRUE
J 2
(5925 1625);
DISPLAY 0.872340 (5925 1625);
PAINT ORANGE (5925 1625);
DISPLAY INVISIBLE (5925 1625);
FORCEPROP 1 LAST PATH I297
J 2
(6252 1750);
DISPLAY 0.872340 (6252 1750);
PAINT GREEN (6252 1750);
DISPLAY INVISIBLE (6252 1750);
FORCEADD TAP..1
R 2
(6250 1550);
FORCEPROP 3 LASTPIN (6300 1550) SIG_NAME P3E_CPU0_PE3_OCP_RXN<11>
J 0
(6310 1560);
DISPLAY 0.659574 (6310 1560);
PAINT MONO (6310 1560);
DISPLAY INVISIBLE (6310 1560);
FORCEPROP 1 LASTPIN (6300 1550) BN 11
J 2
(6312 1558);
DISPLAY 0.617021 (6312 1558);
PAINT GREEN (6312 1558);
FORCEPROP 2 LAST CDS_LIB mstr_standard
J 0
(6250 1550);
PAINT ORANGE (6250 1550);
DISPLAY INVISIBLE (6250 1550);
FORCEPROP 1 LAST BODY_TYPE PLUMBING
J 2
(6250 1600);
DISPLAY 0.872340 (6250 1600);
PAINT GREEN (6250 1600);
DISPLAY INVISIBLE (6250 1600);
FORCEPROP 1 LAST HDL_TAP TRUE
J 2
(5925 1425);
DISPLAY 0.872340 (5925 1425);
PAINT ORANGE (5925 1425);
DISPLAY INVISIBLE (5925 1425);
FORCEPROP 1 LAST PATH I298
J 2
(6252 1550);
DISPLAY 0.872340 (6252 1550);
PAINT GREEN (6252 1550);
DISPLAY INVISIBLE (6252 1550);
FORCEADD TAP..1
R 2
(6250 1350);
FORCEPROP 3 LASTPIN (6300 1350) SIG_NAME P3E_CPU0_PE3_OCP_RXN<10>
J 0
(6310 1360);
DISPLAY 0.659574 (6310 1360);
PAINT MONO (6310 1360);
DISPLAY INVISIBLE (6310 1360);
FORCEPROP 1 LASTPIN (6300 1350) BN 10
J 2
(6312 1358);
DISPLAY 0.617021 (6312 1358);
PAINT GREEN (6312 1358);
FORCEPROP 2 LAST CDS_LIB mstr_standard
J 0
(6250 1350);
PAINT ORANGE (6250 1350);
DISPLAY INVISIBLE (6250 1350);
FORCEPROP 1 LAST BODY_TYPE PLUMBING
J 2
(6250 1400);
DISPLAY 0.872340 (6250 1400);
PAINT GREEN (6250 1400);
DISPLAY INVISIBLE (6250 1400);
FORCEPROP 1 LAST HDL_TAP TRUE
J 2
(5925 1225);
DISPLAY 0.872340 (5925 1225);
PAINT ORANGE (5925 1225);
DISPLAY INVISIBLE (5925 1225);
FORCEPROP 1 LAST PATH I299
J 2
(6252 1350);
DISPLAY 0.872340 (6252 1350);
PAINT GREEN (6252 1350);
DISPLAY INVISIBLE (6252 1350);
FORCEADD CAP..1
(10450 3975);
FORCEPROP 1 LASTPIN (10450 3875) $PN 2
J 0
(10460 3855);
DISPLAY 0.617021 (10460 3855);
PAINT ORANGE (10460 3855);
FORCEPROP 1 LASTPIN (10450 4075) $PN 1
J 0
(10460 4055);
DISPLAY 0.617021 (10460 4055);
PAINT ORANGE (10460 4055);
FORCEPROP 1 LAST MATERIAL X6S
J 0
(10500 3875);
DISPLAY 0.617021 (10500 3875);
PAINT SKYBLUE (10500 3875);
FORCEPROP 1 LAST VOLTAGE 16V
J 0
(10500 3975);
DISPLAY 0.617021 (10500 3975);
PAINT SKYBLUE (10500 3975);
FORCEPROP 1 LAST PACK_TYPE 0805
J 0
(10500 3775);
DISPLAY 0.617021 (10500 3775);
PAINT SKYBLUE (10500 3775);
FORCEPROP 1 LAST TOLERANCE 10%
J 0
(10500 3925);
DISPLAY 0.617021 (10500 3925);
PAINT SKYBLUE (10500 3925);
FORCEPROP 1 LAST VALUE 10UF
J 0
(10500 4025);
DISPLAY 0.617021 (10500 4025);
PAINT SKYBLUE (10500 4025);
FORCEPROP 1 LAST PART_NUMBER C95333-007
J 0
(10500 3825);
DISPLAY 0.617021 (10500 3825);
PAINT BLUE (10500 3825);
FORCEPROP 1 LAST LOCATION C1M27
J 0
(10500 4075);
DISPLAY 0.617021 (10500 4075);
PAINT AQUA (10500 4075);
FORCEPROP 2 LAST SEC_TYPE 0805
J 0
(10500 4175);
DISPLAY 1.021277 (10500 4175);
PAINT ORANGE (10500 4175);
DISPLAY INVISIBLE (10500 4175);
FORCEPROP 2 LAST CDS_LIB mstr_discrete
J 0
(10450 3975);
PAINT ORANGE (10450 3975);
DISPLAY INVISIBLE (10450 3975);
FORCEPROP 2 LAST SEC 1
J 0
(10500 4175);
DISPLAY 0.680851 (10500 4175);
PAINT MONO (10500 4175);
DISPLAY INVISIBLE (10500 4175);
FORCEPROP 2 LAST CDS_LOCATION C1M27
J 0
(10500 4075);
DISPLAY 0.617021 (10500 4075);
PAINT AQUA (10500 4075);
DISPLAY INVISIBLE (10500 4075);
FORCEPROP 1 LAST PATH I3
J 0
(10500 4125);
DISPLAY 0.978723 (10500 4125);
PAINT WHITE (10500 4125);
DISPLAY INVISIBLE (10500 4125);
FORCEPROP 0 LAST ROOM IO_SLOT
J 0
(10500 4175);
DISPLAY 1.021277 (10500 4175);
PAINT ORANGE (10500 4175);
DISPLAY INVISIBLE (10500 4175);
FORCEADD TAP..1
R 2
(6425 1000);
FORCEPROP 3 LASTPIN (6475 1000) SIG_NAME P3E_CPU0_PE3_OCP_RXP<8>
J 0
(6485 1010);
DISPLAY 0.659574 (6485 1010);
PAINT MONO (6485 1010);
DISPLAY INVISIBLE (6485 1010);
FORCEPROP 1 LASTPIN (6475 1000) BN 8
J 2
(6487 1008);
DISPLAY 0.617021 (6487 1008);
PAINT GREEN (6487 1008);
FORCEPROP 2 LAST CDS_LIB mstr_standard
J 0
(6425 1000);
PAINT ORANGE (6425 1000);
DISPLAY INVISIBLE (6425 1000);
FORCEPROP 1 LAST BODY_TYPE PLUMBING
J 2
(6425 1050);
DISPLAY 0.872340 (6425 1050);
PAINT GREEN (6425 1050);
DISPLAY INVISIBLE (6425 1050);
FORCEPROP 1 LAST HDL_TAP TRUE
J 2
(6100 875);
DISPLAY 0.872340 (6100 875);
PAINT ORANGE (6100 875);
DISPLAY INVISIBLE (6100 875);
FORCEPROP 1 LAST PATH I300
J 2
(6427 1000);
DISPLAY 0.872340 (6427 1000);
PAINT GREEN (6427 1000);
DISPLAY INVISIBLE (6427 1000);
FORCEADD TAP..1
R 2
(6425 2200);
FORCEPROP 3 LASTPIN (6475 2200) SIG_NAME P3E_CPU0_PE3_OCP_RXP<14>
J 0
(6485 2210);
DISPLAY 0.659574 (6485 2210);
PAINT MONO (6485 2210);
DISPLAY INVISIBLE (6485 2210);
FORCEPROP 1 LASTPIN (6475 2200) BN 14
J 2
(6487 2208);
DISPLAY 0.617021 (6487 2208);
PAINT GREEN (6487 2208);
FORCEPROP 2 LAST CDS_LIB mstr_standard
J 0
(6425 2200);
PAINT ORANGE (6425 2200);
DISPLAY INVISIBLE (6425 2200);
FORCEPROP 1 LAST BODY_TYPE PLUMBING
J 2
(6425 2250);
DISPLAY 0.872340 (6425 2250);
PAINT GREEN (6425 2250);
DISPLAY INVISIBLE (6425 2250);
FORCEPROP 1 LAST HDL_TAP TRUE
J 2
(6100 2075);
DISPLAY 0.872340 (6100 2075);
PAINT ORANGE (6100 2075);
DISPLAY INVISIBLE (6100 2075);
FORCEPROP 1 LAST PATH I301
J 2
(6427 2200);
DISPLAY 0.872340 (6427 2200);
PAINT GREEN (6427 2200);
DISPLAY INVISIBLE (6427 2200);
FORCEADD TAP..1
R 2
(6425 2400);
FORCEPROP 3 LASTPIN (6475 2400) SIG_NAME P3E_CPU0_PE3_OCP_RXP<15>
J 0
(6485 2410);
DISPLAY 0.659574 (6485 2410);
PAINT MONO (6485 2410);
DISPLAY INVISIBLE (6485 2410);
FORCEPROP 1 LASTPIN (6475 2400) BN 15
J 2
(6487 2408);
DISPLAY 0.617021 (6487 2408);
PAINT GREEN (6487 2408);
FORCEPROP 2 LAST CDS_LIB mstr_standard
J 0
(6425 2400);
PAINT ORANGE (6425 2400);
DISPLAY INVISIBLE (6425 2400);
FORCEPROP 1 LAST BODY_TYPE PLUMBING
J 2
(6425 2450);
DISPLAY 0.872340 (6425 2450);
PAINT GREEN (6425 2450);
DISPLAY INVISIBLE (6425 2450);
FORCEPROP 1 LAST HDL_TAP TRUE
J 2
(6100 2275);
DISPLAY 0.872340 (6100 2275);
PAINT ORANGE (6100 2275);
DISPLAY INVISIBLE (6100 2275);
FORCEPROP 1 LAST PATH I302
J 2
(6427 2400);
DISPLAY 0.872340 (6427 2400);
PAINT GREEN (6427 2400);
DISPLAY INVISIBLE (6427 2400);
FORCEADD TAP..1
R 2
(6250 2350);
FORCEPROP 3 LASTPIN (6300 2350) SIG_NAME P3E_CPU0_PE3_OCP_RXN<15>
J 0
(6310 2360);
DISPLAY 0.659574 (6310 2360);
PAINT MONO (6310 2360);
DISPLAY INVISIBLE (6310 2360);
FORCEPROP 1 LASTPIN (6300 2350) BN 15
J 2
(6312 2358);
DISPLAY 0.617021 (6312 2358);
PAINT GREEN (6312 2358);
FORCEPROP 2 LAST CDS_LIB mstr_standard
J 0
(6250 2350);
PAINT ORANGE (6250 2350);
DISPLAY INVISIBLE (6250 2350);
FORCEPROP 1 LAST BODY_TYPE PLUMBING
J 2
(6250 2400);
DISPLAY 0.872340 (6250 2400);
PAINT GREEN (6250 2400);
DISPLAY INVISIBLE (6250 2400);
FORCEPROP 1 LAST HDL_TAP TRUE
J 2
(5925 2225);
DISPLAY 0.872340 (5925 2225);
PAINT ORANGE (5925 2225);
DISPLAY INVISIBLE (5925 2225);
FORCEPROP 1 LAST PATH I303
J 2
(6252 2350);
DISPLAY 0.872340 (6252 2350);
PAINT GREEN (6252 2350);
DISPLAY INVISIBLE (6252 2350);
FORCEADD TAP..1
R 2
(6425 2000);
FORCEPROP 3 LASTPIN (6475 2000) SIG_NAME P3E_CPU0_PE3_OCP_RXP<13>
J 0
(6485 2010);
DISPLAY 0.659574 (6485 2010);
PAINT MONO (6485 2010);
DISPLAY INVISIBLE (6485 2010);
FORCEPROP 1 LASTPIN (6475 2000) BN 13
J 2
(6487 2008);
DISPLAY 0.617021 (6487 2008);
PAINT GREEN (6487 2008);
FORCEPROP 2 LAST CDS_LIB mstr_standard
J 0
(6425 2000);
PAINT ORANGE (6425 2000);
DISPLAY INVISIBLE (6425 2000);
FORCEPROP 1 LAST BODY_TYPE PLUMBING
J 2
(6425 2050);
DISPLAY 0.872340 (6425 2050);
PAINT GREEN (6425 2050);
DISPLAY INVISIBLE (6425 2050);
FORCEPROP 1 LAST HDL_TAP TRUE
J 2
(6100 1875);
DISPLAY 0.872340 (6100 1875);
PAINT ORANGE (6100 1875);
DISPLAY INVISIBLE (6100 1875);
FORCEPROP 1 LAST PATH I304
J 2
(6427 2000);
DISPLAY 0.872340 (6427 2000);
PAINT GREEN (6427 2000);
DISPLAY INVISIBLE (6427 2000);
FORCEADD TAP..1
R 2
(6425 1800);
FORCEPROP 3 LASTPIN (6475 1800) SIG_NAME P3E_CPU0_PE3_OCP_RXP<12>
J 0
(6485 1810);
DISPLAY 0.659574 (6485 1810);
PAINT MONO (6485 1810);
DISPLAY INVISIBLE (6485 1810);
FORCEPROP 1 LASTPIN (6475 1800) BN 12
J 2
(6487 1808);
DISPLAY 0.617021 (6487 1808);
PAINT GREEN (6487 1808);
FORCEPROP 2 LAST CDS_LIB mstr_standard
J 0
(6425 1800);
PAINT ORANGE (6425 1800);
DISPLAY INVISIBLE (6425 1800);
FORCEPROP 1 LAST BODY_TYPE PLUMBING
J 2
(6425 1850);
DISPLAY 0.872340 (6425 1850);
PAINT GREEN (6425 1850);
DISPLAY INVISIBLE (6425 1850);
FORCEPROP 1 LAST HDL_TAP TRUE
J 2
(6100 1675);
DISPLAY 0.872340 (6100 1675);
PAINT ORANGE (6100 1675);
DISPLAY INVISIBLE (6100 1675);
FORCEPROP 1 LAST PATH I305
J 2
(6427 1800);
DISPLAY 0.872340 (6427 1800);
PAINT GREEN (6427 1800);
DISPLAY INVISIBLE (6427 1800);
FORCEADD TAP..1
R 2
(6250 2150);
FORCEPROP 3 LASTPIN (6300 2150) SIG_NAME P3E_CPU0_PE3_OCP_RXN<14>
J 0
(6310 2160);
DISPLAY 0.659574 (6310 2160);
PAINT MONO (6310 2160);
DISPLAY INVISIBLE (6310 2160);
FORCEPROP 1 LASTPIN (6300 2150) BN 14
J 2
(6312 2158);
DISPLAY 0.617021 (6312 2158);
PAINT GREEN (6312 2158);
FORCEPROP 2 LAST CDS_LIB mstr_standard
J 0
(6250 2150);
PAINT ORANGE (6250 2150);
DISPLAY INVISIBLE (6250 2150);
FORCEPROP 1 LAST BODY_TYPE PLUMBING
J 2
(6250 2200);
DISPLAY 0.872340 (6250 2200);
PAINT GREEN (6250 2200);
DISPLAY INVISIBLE (6250 2200);
FORCEPROP 1 LAST HDL_TAP TRUE
J 2
(5925 2025);
DISPLAY 0.872340 (5925 2025);
PAINT ORANGE (5925 2025);
DISPLAY INVISIBLE (5925 2025);
FORCEPROP 1 LAST PATH I306
J 2
(6252 2150);
DISPLAY 0.872340 (6252 2150);
PAINT GREEN (6252 2150);
DISPLAY INVISIBLE (6252 2150);
FORCEADD TAP..1
R 2
(6250 1950);
FORCEPROP 3 LASTPIN (6300 1950) SIG_NAME P3E_CPU0_PE3_OCP_RXN<13>
J 0
(6310 1960);
DISPLAY 0.659574 (6310 1960);
PAINT MONO (6310 1960);
DISPLAY INVISIBLE (6310 1960);
FORCEPROP 1 LASTPIN (6300 1950) BN 13
J 2
(6312 1958);
DISPLAY 0.617021 (6312 1958);
PAINT GREEN (6312 1958);
FORCEPROP 2 LAST CDS_LIB mstr_standard
J 0
(6250 1950);
PAINT ORANGE (6250 1950);
DISPLAY INVISIBLE (6250 1950);
FORCEPROP 1 LAST BODY_TYPE PLUMBING
J 2
(6250 2000);
DISPLAY 0.872340 (6250 2000);
PAINT GREEN (6250 2000);
DISPLAY INVISIBLE (6250 2000);
FORCEPROP 1 LAST HDL_TAP TRUE
J 2
(5925 1825);
DISPLAY 0.872340 (5925 1825);
PAINT ORANGE (5925 1825);
DISPLAY INVISIBLE (5925 1825);
FORCEPROP 1 LAST PATH I307
J 2
(6252 1950);
DISPLAY 0.872340 (6252 1950);
PAINT GREEN (6252 1950);
DISPLAY INVISIBLE (6252 1950);
FORCEADD TAP..1
R 2
(6425 1600);
FORCEPROP 3 LASTPIN (6475 1600) SIG_NAME P3E_CPU0_PE3_OCP_RXP<11>
J 0
(6485 1610);
DISPLAY 0.659574 (6485 1610);
PAINT MONO (6485 1610);
DISPLAY INVISIBLE (6485 1610);
FORCEPROP 1 LASTPIN (6475 1600) BN 11
J 2
(6487 1608);
DISPLAY 0.617021 (6487 1608);
PAINT GREEN (6487 1608);
FORCEPROP 2 LAST CDS_LIB mstr_standard
J 0
(6425 1600);
PAINT ORANGE (6425 1600);
DISPLAY INVISIBLE (6425 1600);
FORCEPROP 1 LAST BODY_TYPE PLUMBING
J 2
(6425 1650);
DISPLAY 0.872340 (6425 1650);
PAINT GREEN (6425 1650);
DISPLAY INVISIBLE (6425 1650);
FORCEPROP 1 LAST HDL_TAP TRUE
J 2
(6100 1475);
DISPLAY 0.872340 (6100 1475);
PAINT ORANGE (6100 1475);
DISPLAY INVISIBLE (6100 1475);
FORCEPROP 1 LAST PATH I308
J 2
(6427 1600);
DISPLAY 0.872340 (6427 1600);
PAINT GREEN (6427 1600);
DISPLAY INVISIBLE (6427 1600);
FORCEADD TAP..1
R 2
(6425 1400);
FORCEPROP 3 LASTPIN (6475 1400) SIG_NAME P3E_CPU0_PE3_OCP_RXP<10>
J 0
(6485 1410);
DISPLAY 0.659574 (6485 1410);
PAINT MONO (6485 1410);
DISPLAY INVISIBLE (6485 1410);
FORCEPROP 1 LASTPIN (6475 1400) BN 10
J 2
(6487 1408);
DISPLAY 0.617021 (6487 1408);
PAINT GREEN (6487 1408);
FORCEPROP 2 LAST CDS_LIB mstr_standard
J 0
(6425 1400);
PAINT ORANGE (6425 1400);
DISPLAY INVISIBLE (6425 1400);
FORCEPROP 1 LAST BODY_TYPE PLUMBING
J 2
(6425 1450);
DISPLAY 0.872340 (6425 1450);
PAINT GREEN (6425 1450);
DISPLAY INVISIBLE (6425 1450);
FORCEPROP 1 LAST HDL_TAP TRUE
J 2
(6100 1275);
DISPLAY 0.872340 (6100 1275);
PAINT ORANGE (6100 1275);
DISPLAY INVISIBLE (6100 1275);
FORCEPROP 1 LAST PATH I309
J 2
(6427 1400);
DISPLAY 0.872340 (6427 1400);
PAINT GREEN (6427 1400);
DISPLAY INVISIBLE (6427 1400);
FORCEADD TAP..1
R 2
(6425 1200);
FORCEPROP 3 LASTPIN (6475 1200) SIG_NAME P3E_CPU0_PE3_OCP_RXP<9>
J 0
(6485 1210);
DISPLAY 0.659574 (6485 1210);
PAINT MONO (6485 1210);
DISPLAY INVISIBLE (6485 1210);
FORCEPROP 1 LASTPIN (6475 1200) BN 9
J 2
(6487 1208);
DISPLAY 0.617021 (6487 1208);
PAINT GREEN (6487 1208);
FORCEPROP 2 LAST CDS_LIB mstr_standard
J 0
(6425 1200);
PAINT ORANGE (6425 1200);
DISPLAY INVISIBLE (6425 1200);
FORCEPROP 1 LAST BODY_TYPE PLUMBING
J 2
(6425 1250);
DISPLAY 0.872340 (6425 1250);
PAINT GREEN (6425 1250);
DISPLAY INVISIBLE (6425 1250);
FORCEPROP 1 LAST HDL_TAP TRUE
J 2
(6100 1075);
DISPLAY 0.872340 (6100 1075);
PAINT ORANGE (6100 1075);
DISPLAY INVISIBLE (6100 1075);
FORCEPROP 1 LAST PATH I310
J 2
(6427 1200);
DISPLAY 0.872340 (6427 1200);
PAINT GREEN (6427 1200);
DISPLAY INVISIBLE (6427 1200);
FORCEADD TAP..1
R 2
(6250 1150);
FORCEPROP 3 LASTPIN (6300 1150) SIG_NAME P3E_CPU0_PE3_OCP_RXN<9>
J 0
(6310 1160);
DISPLAY 0.659574 (6310 1160);
PAINT MONO (6310 1160);
DISPLAY INVISIBLE (6310 1160);
FORCEPROP 1 LASTPIN (6300 1150) BN 9
J 2
(6312 1158);
DISPLAY 0.617021 (6312 1158);
PAINT GREEN (6312 1158);
FORCEPROP 2 LAST CDS_LIB mstr_standard
J 0
(6250 1150);
PAINT ORANGE (6250 1150);
DISPLAY INVISIBLE (6250 1150);
FORCEPROP 1 LAST BODY_TYPE PLUMBING
J 2
(6250 1200);
DISPLAY 0.872340 (6250 1200);
PAINT GREEN (6250 1200);
DISPLAY INVISIBLE (6250 1200);
FORCEPROP 1 LAST HDL_TAP TRUE
J 2
(5925 1025);
DISPLAY 0.872340 (5925 1025);
PAINT ORANGE (5925 1025);
DISPLAY INVISIBLE (5925 1025);
FORCEPROP 1 LAST PATH I311
J 2
(6252 1150);
DISPLAY 0.872340 (6252 1150);
PAINT GREEN (6252 1150);
DISPLAY INVISIBLE (6252 1150);
FORCEADD TAP..1
R 2
(6250 950);
FORCEPROP 3 LASTPIN (6300 950) SIG_NAME P3E_CPU0_PE3_OCP_RXN<8>
J 0
(6310 960);
DISPLAY 0.659574 (6310 960);
PAINT MONO (6310 960);
DISPLAY INVISIBLE (6310 960);
FORCEPROP 1 LASTPIN (6300 950) BN 8
J 2
(6312 958);
DISPLAY 0.617021 (6312 958);
PAINT GREEN (6312 958);
FORCEPROP 2 LAST CDS_LIB mstr_standard
J 0
(6250 950);
PAINT ORANGE (6250 950);
DISPLAY INVISIBLE (6250 950);
FORCEPROP 1 LAST BODY_TYPE PLUMBING
J 2
(6250 1000);
DISPLAY 0.872340 (6250 1000);
PAINT GREEN (6250 1000);
DISPLAY INVISIBLE (6250 1000);
FORCEPROP 1 LAST HDL_TAP TRUE
J 2
(5925 825);
DISPLAY 0.872340 (5925 825);
PAINT ORANGE (5925 825);
DISPLAY INVISIBLE (5925 825);
FORCEPROP 1 LAST PATH I312
J 2
(6252 950);
DISPLAY 0.872340 (6252 950);
PAINT GREEN (6252 950);
DISPLAY INVISIBLE (6252 950);
FORCEADD OFFPAGE..2
R 2
(5150 2575);
FORCEPROP 2 LAST $XR0 32 
J 0
(4926 2575);
DISPLAY 0.638298 (4926 2575);
PAINT MONO (4926 2575);
FORCEPROP 2 LAST PATH I313
J 2
(5400 2625);
DISPLAY 1.021277 (5400 2625);
PAINT ORANGE (5400 2625);
DISPLAY INVISIBLE (5400 2625);
FORCEPROP 1 LAST COMMENT_BODY TRUE
J 2
(5195 2480);
DISPLAY 0.872340 (5195 2480);
PAINT GREEN (5195 2480);
DISPLAY INVISIBLE (5195 2480);
FORCEPROP 1 LAST OFFPAGE TRUE
J 2
(4825 2450);
DISPLAY 0.872340 (4825 2450);
PAINT GREEN (4825 2450);
DISPLAY INVISIBLE (4825 2450);
FORCEPROP 2 LAST CDS_LIB mstr_standard
J 2
(5150 2575);
PAINT MONO (5150 2575);
DISPLAY INVISIBLE (5150 2575);
FORCEADD OFFPAGE..2
R 2
(5150 2625);
FORCEPROP 2 LAST $XR0 32 
J 0
(4926 2625);
DISPLAY 0.638298 (4926 2625);
PAINT MONO (4926 2625);
FORCEPROP 2 LAST PATH I314
J 2
(5400 2675);
DISPLAY 1.021277 (5400 2675);
PAINT ORANGE (5400 2675);
DISPLAY INVISIBLE (5400 2675);
FORCEPROP 1 LAST COMMENT_BODY TRUE
J 2
(5195 2530);
DISPLAY 0.872340 (5195 2530);
PAINT GREEN (5195 2530);
DISPLAY INVISIBLE (5195 2530);
FORCEPROP 1 LAST OFFPAGE TRUE
J 2
(4825 2500);
DISPLAY 0.872340 (4825 2500);
PAINT GREEN (4825 2500);
DISPLAY INVISIBLE (4825 2500);
FORCEPROP 2 LAST CDS_LIB mstr_standard
J 2
(5150 2625);
PAINT MONO (5150 2625);
DISPLAY INVISIBLE (5150 2625);
FORCEADD TAP..1
(10250 1850);
FORCEPROP 3 LASTPIN (10200 1850) SIG_NAME P3E_OCP_CPU0_PE3_C_TXN<12>
J 0
(10210 1860);
DISPLAY 0.659574 (10210 1860);
PAINT MONO (10210 1860);
DISPLAY INVISIBLE (10210 1860);
FORCEPROP 1 LASTPIN (10200 1850) BN 12
J 0
(10188 1858);
DISPLAY 0.617021 (10188 1858);
PAINT GREEN (10188 1858);
FORCEPROP 2 LAST CDS_LIB mstr_standard
J 0
(10250 1850);
PAINT ORANGE (10250 1850);
DISPLAY INVISIBLE (10250 1850);
FORCEPROP 1 LAST BODY_TYPE PLUMBING
J 0
(10250 1900);
DISPLAY 0.872340 (10250 1900);
PAINT GREEN (10250 1900);
DISPLAY INVISIBLE (10250 1900);
FORCEPROP 1 LAST HDL_TAP TRUE
J 0
(10575 1725);
DISPLAY 0.872340 (10575 1725);
PAINT ORANGE (10575 1725);
DISPLAY INVISIBLE (10575 1725);
FORCEPROP 1 LAST PATH I315
J 0
(10248 1850);
DISPLAY 0.872340 (10248 1850);
PAINT GREEN (10248 1850);
DISPLAY INVISIBLE (10248 1850);
FORCEADD TAP..1
(10050 2100);
FORCEPROP 3 LASTPIN (10000 2100) SIG_NAME P3E_OCP_CPU0_PE3_C_TXP<13>
J 0
(10010 2110);
DISPLAY 0.659574 (10010 2110);
PAINT MONO (10010 2110);
DISPLAY INVISIBLE (10010 2110);
FORCEPROP 1 LASTPIN (10000 2100) BN 13
J 0
(9988 2108);
DISPLAY 0.617021 (9988 2108);
PAINT GREEN (9988 2108);
FORCEPROP 2 LAST CDS_LIB mstr_standard
J 0
(10050 2100);
PAINT ORANGE (10050 2100);
DISPLAY INVISIBLE (10050 2100);
FORCEPROP 1 LAST BODY_TYPE PLUMBING
J 0
(10050 2150);
DISPLAY 0.872340 (10050 2150);
PAINT GREEN (10050 2150);
DISPLAY INVISIBLE (10050 2150);
FORCEPROP 1 LAST HDL_TAP TRUE
J 0
(10375 1975);
DISPLAY 0.872340 (10375 1975);
PAINT ORANGE (10375 1975);
DISPLAY INVISIBLE (10375 1975);
FORCEPROP 1 LAST PATH I316
J 0
(10048 2100);
DISPLAY 0.872340 (10048 2100);
PAINT GREEN (10048 2100);
DISPLAY INVISIBLE (10048 2100);
FORCEADD TAP..1
(10050 2300);
FORCEPROP 3 LASTPIN (10000 2300) SIG_NAME P3E_OCP_CPU0_PE3_C_TXP<14>
J 0
(10010 2310);
DISPLAY 0.659574 (10010 2310);
PAINT MONO (10010 2310);
DISPLAY INVISIBLE (10010 2310);
FORCEPROP 1 LASTPIN (10000 2300) BN 14
J 0
(9988 2308);
DISPLAY 0.617021 (9988 2308);
PAINT GREEN (9988 2308);
FORCEPROP 2 LAST CDS_LIB mstr_standard
J 0
(10050 2300);
PAINT ORANGE (10050 2300);
DISPLAY INVISIBLE (10050 2300);
FORCEPROP 1 LAST BODY_TYPE PLUMBING
J 0
(10050 2350);
DISPLAY 0.872340 (10050 2350);
PAINT GREEN (10050 2350);
DISPLAY INVISIBLE (10050 2350);
FORCEPROP 1 LAST HDL_TAP TRUE
J 0
(10375 2175);
DISPLAY 0.872340 (10375 2175);
PAINT ORANGE (10375 2175);
DISPLAY INVISIBLE (10375 2175);
FORCEPROP 1 LAST PATH I317
J 0
(10048 2300);
DISPLAY 0.872340 (10048 2300);
PAINT GREEN (10048 2300);
DISPLAY INVISIBLE (10048 2300);
FORCEADD TAP..1
(10050 2500);
FORCEPROP 3 LASTPIN (10000 2500) SIG_NAME P3E_OCP_CPU0_PE3_C_TXP<15>
J 0
(10010 2510);
DISPLAY 0.659574 (10010 2510);
PAINT MONO (10010 2510);
DISPLAY INVISIBLE (10010 2510);
FORCEPROP 1 LASTPIN (10000 2500) BN 15
J 0
(9988 2508);
DISPLAY 0.617021 (9988 2508);
PAINT GREEN (9988 2508);
FORCEPROP 2 LAST CDS_LIB mstr_standard
J 0
(10050 2500);
PAINT ORANGE (10050 2500);
DISPLAY INVISIBLE (10050 2500);
FORCEPROP 1 LAST BODY_TYPE PLUMBING
J 0
(10050 2550);
DISPLAY 0.872340 (10050 2550);
PAINT GREEN (10050 2550);
DISPLAY INVISIBLE (10050 2550);
FORCEPROP 1 LAST HDL_TAP TRUE
J 0
(10375 2375);
DISPLAY 0.872340 (10375 2375);
PAINT ORANGE (10375 2375);
DISPLAY INVISIBLE (10375 2375);
FORCEPROP 1 LAST PATH I318
J 0
(10048 2500);
DISPLAY 0.872340 (10048 2500);
PAINT GREEN (10048 2500);
DISPLAY INVISIBLE (10048 2500);
FORCEADD OFFPAGE..1
R 2
(11025 2500);
FORCEPROP 2 LAST $XR0 106 
J 0
(11211 2500);
DISPLAY 0.638298 (11211 2500);
PAINT MONO (11211 2500);
FORCEPROP 2 LAST PATH I320
J 2
(10850 2575);
DISPLAY 1.021277 (10850 2575);
PAINT ORANGE (10850 2575);
DISPLAY INVISIBLE (10850 2575);
FORCEPROP 1 LAST COMMENT_BODY TRUE
J 2
(10900 2400);
DISPLAY 0.872340 (10900 2400);
PAINT GREEN (10900 2400);
DISPLAY INVISIBLE (10900 2400);
FORCEPROP 1 LAST OFFPAGE TRUE
J 2
(10700 2375);
DISPLAY 0.872340 (10700 2375);
PAINT GREEN (10700 2375);
DISPLAY INVISIBLE (10700 2375);
FORCEPROP 2 LAST CDS_LIB mstr_standard
J 2
(11025 2500);
PAINT ORANGE (11025 2500);
DISPLAY INVISIBLE (11025 2500);
FORCEADD TAP..1
(10250 2450);
FORCEPROP 3 LASTPIN (10200 2450) SIG_NAME P3E_OCP_CPU0_PE3_C_TXN<15>
J 0
(10210 2460);
DISPLAY 0.659574 (10210 2460);
PAINT MONO (10210 2460);
DISPLAY INVISIBLE (10210 2460);
FORCEPROP 1 LASTPIN (10200 2450) BN 15
J 0
(10188 2458);
DISPLAY 0.617021 (10188 2458);
PAINT GREEN (10188 2458);
FORCEPROP 2 LAST CDS_LIB mstr_standard
J 0
(10250 2450);
PAINT ORANGE (10250 2450);
DISPLAY INVISIBLE (10250 2450);
FORCEPROP 1 LAST BODY_TYPE PLUMBING
J 0
(10250 2500);
DISPLAY 0.872340 (10250 2500);
PAINT GREEN (10250 2500);
DISPLAY INVISIBLE (10250 2500);
FORCEPROP 1 LAST HDL_TAP TRUE
J 0
(10575 2325);
DISPLAY 0.872340 (10575 2325);
PAINT ORANGE (10575 2325);
DISPLAY INVISIBLE (10575 2325);
FORCEPROP 1 LAST PATH I321
J 0
(10248 2450);
DISPLAY 0.872340 (10248 2450);
PAINT GREEN (10248 2450);
DISPLAY INVISIBLE (10248 2450);
FORCEADD TAP..1
(10250 2250);
FORCEPROP 3 LASTPIN (10200 2250) SIG_NAME P3E_OCP_CPU0_PE3_C_TXN<14>
J 0
(10210 2260);
DISPLAY 0.659574 (10210 2260);
PAINT MONO (10210 2260);
DISPLAY INVISIBLE (10210 2260);
FORCEPROP 1 LASTPIN (10200 2250) BN 14
J 0
(10188 2258);
DISPLAY 0.617021 (10188 2258);
PAINT GREEN (10188 2258);
FORCEPROP 2 LAST CDS_LIB mstr_standard
J 0
(10250 2250);
PAINT ORANGE (10250 2250);
DISPLAY INVISIBLE (10250 2250);
FORCEPROP 1 LAST BODY_TYPE PLUMBING
J 0
(10250 2300);
DISPLAY 0.872340 (10250 2300);
PAINT GREEN (10250 2300);
DISPLAY INVISIBLE (10250 2300);
FORCEPROP 1 LAST HDL_TAP TRUE
J 0
(10575 2125);
DISPLAY 0.872340 (10575 2125);
PAINT ORANGE (10575 2125);
DISPLAY INVISIBLE (10575 2125);
FORCEPROP 1 LAST PATH I322
J 0
(10248 2250);
DISPLAY 0.872340 (10248 2250);
PAINT GREEN (10248 2250);
DISPLAY INVISIBLE (10248 2250);
FORCEADD TAP..1
(10250 2050);
FORCEPROP 3 LASTPIN (10200 2050) SIG_NAME P3E_OCP_CPU0_PE3_C_TXN<13>
J 0
(10210 2060);
DISPLAY 0.659574 (10210 2060);
PAINT MONO (10210 2060);
DISPLAY INVISIBLE (10210 2060);
FORCEPROP 1 LASTPIN (10200 2050) BN 13
J 0
(10188 2058);
DISPLAY 0.617021 (10188 2058);
PAINT GREEN (10188 2058);
FORCEPROP 2 LAST CDS_LIB mstr_standard
J 0
(10250 2050);
PAINT ORANGE (10250 2050);
DISPLAY INVISIBLE (10250 2050);
FORCEPROP 1 LAST BODY_TYPE PLUMBING
J 0
(10250 2100);
DISPLAY 0.872340 (10250 2100);
PAINT GREEN (10250 2100);
DISPLAY INVISIBLE (10250 2100);
FORCEPROP 1 LAST HDL_TAP TRUE
J 0
(10575 1925);
DISPLAY 0.872340 (10575 1925);
PAINT ORANGE (10575 1925);
DISPLAY INVISIBLE (10575 1925);
FORCEPROP 1 LAST PATH I323
J 0
(10248 2050);
DISPLAY 0.872340 (10248 2050);
PAINT GREEN (10248 2050);
DISPLAY INVISIBLE (10248 2050);
FORCEADD TAP..1
(10250 1650);
FORCEPROP 3 LASTPIN (10200 1650) SIG_NAME P3E_OCP_CPU0_PE3_C_TXN<11>
J 0
(10210 1660);
DISPLAY 0.659574 (10210 1660);
PAINT MONO (10210 1660);
DISPLAY INVISIBLE (10210 1660);
FORCEPROP 1 LASTPIN (10200 1650) BN 11
J 0
(10188 1658);
DISPLAY 0.617021 (10188 1658);
PAINT GREEN (10188 1658);
FORCEPROP 2 LAST CDS_LIB mstr_standard
J 0
(10250 1650);
PAINT ORANGE (10250 1650);
DISPLAY INVISIBLE (10250 1650);
FORCEPROP 1 LAST BODY_TYPE PLUMBING
J 0
(10250 1700);
DISPLAY 0.872340 (10250 1700);
PAINT GREEN (10250 1700);
DISPLAY INVISIBLE (10250 1700);
FORCEPROP 1 LAST HDL_TAP TRUE
J 0
(10575 1525);
DISPLAY 0.872340 (10575 1525);
PAINT ORANGE (10575 1525);
DISPLAY INVISIBLE (10575 1525);
FORCEPROP 1 LAST PATH I324
J 0
(10248 1650);
DISPLAY 0.872340 (10248 1650);
PAINT GREEN (10248 1650);
DISPLAY INVISIBLE (10248 1650);
FORCEADD TAP..1
(10050 1700);
FORCEPROP 3 LASTPIN (10000 1700) SIG_NAME P3E_OCP_CPU0_PE3_C_TXP<11>
J 0
(10010 1710);
DISPLAY 0.659574 (10010 1710);
PAINT MONO (10010 1710);
DISPLAY INVISIBLE (10010 1710);
FORCEPROP 1 LASTPIN (10000 1700) BN 11
J 0
(9988 1708);
DISPLAY 0.617021 (9988 1708);
PAINT GREEN (9988 1708);
FORCEPROP 2 LAST CDS_LIB mstr_standard
J 0
(10050 1700);
PAINT ORANGE (10050 1700);
DISPLAY INVISIBLE (10050 1700);
FORCEPROP 1 LAST BODY_TYPE PLUMBING
J 0
(10050 1750);
DISPLAY 0.872340 (10050 1750);
PAINT GREEN (10050 1750);
DISPLAY INVISIBLE (10050 1750);
FORCEPROP 1 LAST HDL_TAP TRUE
J 0
(10375 1575);
DISPLAY 0.872340 (10375 1575);
PAINT ORANGE (10375 1575);
DISPLAY INVISIBLE (10375 1575);
FORCEPROP 1 LAST PATH I325
J 0
(10048 1700);
DISPLAY 0.872340 (10048 1700);
PAINT GREEN (10048 1700);
DISPLAY INVISIBLE (10048 1700);
FORCEADD TAP..1
(10050 1900);
FORCEPROP 3 LASTPIN (10000 1900) SIG_NAME P3E_OCP_CPU0_PE3_C_TXP<12>
J 0
(10010 1910);
DISPLAY 0.659574 (10010 1910);
PAINT MONO (10010 1910);
DISPLAY INVISIBLE (10010 1910);
FORCEPROP 1 LASTPIN (10000 1900) BN 12
J 0
(9988 1908);
DISPLAY 0.617021 (9988 1908);
PAINT GREEN (9988 1908);
FORCEPROP 2 LAST CDS_LIB mstr_standard
J 0
(10050 1900);
PAINT ORANGE (10050 1900);
DISPLAY INVISIBLE (10050 1900);
FORCEPROP 1 LAST BODY_TYPE PLUMBING
J 0
(10050 1950);
DISPLAY 0.872340 (10050 1950);
PAINT GREEN (10050 1950);
DISPLAY INVISIBLE (10050 1950);
FORCEPROP 1 LAST HDL_TAP TRUE
J 0
(10375 1775);
DISPLAY 0.872340 (10375 1775);
PAINT ORANGE (10375 1775);
DISPLAY INVISIBLE (10375 1775);
FORCEPROP 1 LAST PATH I326
J 0
(10048 1900);
DISPLAY 0.872340 (10048 1900);
PAINT GREEN (10048 1900);
DISPLAY INVISIBLE (10048 1900);
FORCEADD TAP..1
(10250 1450);
FORCEPROP 3 LASTPIN (10200 1450) SIG_NAME P3E_OCP_CPU0_PE3_C_TXN<10>
J 0
(10210 1460);
DISPLAY 0.659574 (10210 1460);
PAINT MONO (10210 1460);
DISPLAY INVISIBLE (10210 1460);
FORCEPROP 1 LASTPIN (10200 1450) BN 10
J 0
(10188 1458);
DISPLAY 0.617021 (10188 1458);
PAINT GREEN (10188 1458);
FORCEPROP 2 LAST CDS_LIB mstr_standard
J 0
(10250 1450);
PAINT ORANGE (10250 1450);
DISPLAY INVISIBLE (10250 1450);
FORCEPROP 1 LAST BODY_TYPE PLUMBING
J 0
(10250 1500);
DISPLAY 0.872340 (10250 1500);
PAINT GREEN (10250 1500);
DISPLAY INVISIBLE (10250 1500);
FORCEPROP 1 LAST HDL_TAP TRUE
J 0
(10575 1325);
DISPLAY 0.872340 (10575 1325);
PAINT ORANGE (10575 1325);
DISPLAY INVISIBLE (10575 1325);
FORCEPROP 1 LAST PATH I327
J 0
(10248 1450);
DISPLAY 0.872340 (10248 1450);
PAINT GREEN (10248 1450);
DISPLAY INVISIBLE (10248 1450);
FORCEADD TAP..1
(10250 1250);
FORCEPROP 3 LASTPIN (10200 1250) SIG_NAME P3E_OCP_CPU0_PE3_C_TXN<9>
J 0
(10210 1260);
DISPLAY 0.659574 (10210 1260);
PAINT MONO (10210 1260);
DISPLAY INVISIBLE (10210 1260);
FORCEPROP 1 LASTPIN (10200 1250) BN 9
J 0
(10188 1258);
DISPLAY 0.617021 (10188 1258);
PAINT GREEN (10188 1258);
FORCEPROP 2 LAST CDS_LIB mstr_standard
J 0
(10250 1250);
PAINT ORANGE (10250 1250);
DISPLAY INVISIBLE (10250 1250);
FORCEPROP 1 LAST BODY_TYPE PLUMBING
J 0
(10250 1300);
DISPLAY 0.872340 (10250 1300);
PAINT GREEN (10250 1300);
DISPLAY INVISIBLE (10250 1300);
FORCEPROP 1 LAST HDL_TAP TRUE
J 0
(10575 1125);
DISPLAY 0.872340 (10575 1125);
PAINT ORANGE (10575 1125);
DISPLAY INVISIBLE (10575 1125);
FORCEPROP 1 LAST PATH I328
J 0
(10248 1250);
DISPLAY 0.872340 (10248 1250);
PAINT GREEN (10248 1250);
DISPLAY INVISIBLE (10248 1250);
FORCEADD TAP..1
(10050 1300);
FORCEPROP 3 LASTPIN (10000 1300) SIG_NAME P3E_OCP_CPU0_PE3_C_TXP<9>
J 0
(10010 1310);
DISPLAY 0.659574 (10010 1310);
PAINT MONO (10010 1310);
DISPLAY INVISIBLE (10010 1310);
FORCEPROP 1 LASTPIN (10000 1300) BN 9
J 0
(9988 1308);
DISPLAY 0.617021 (9988 1308);
PAINT GREEN (9988 1308);
FORCEPROP 2 LAST CDS_LIB mstr_standard
J 0
(10050 1300);
PAINT ORANGE (10050 1300);
DISPLAY INVISIBLE (10050 1300);
FORCEPROP 1 LAST BODY_TYPE PLUMBING
J 0
(10050 1350);
DISPLAY 0.872340 (10050 1350);
PAINT GREEN (10050 1350);
DISPLAY INVISIBLE (10050 1350);
FORCEPROP 1 LAST HDL_TAP TRUE
J 0
(10375 1175);
DISPLAY 0.872340 (10375 1175);
PAINT ORANGE (10375 1175);
DISPLAY INVISIBLE (10375 1175);
FORCEPROP 1 LAST PATH I329
J 0
(10048 1300);
DISPLAY 0.872340 (10048 1300);
PAINT GREEN (10048 1300);
DISPLAY INVISIBLE (10048 1300);
FORCEADD TAP..1
(10050 1500);
FORCEPROP 3 LASTPIN (10000 1500) SIG_NAME P3E_OCP_CPU0_PE3_C_TXP<10>
J 0
(10010 1510);
DISPLAY 0.659574 (10010 1510);
PAINT MONO (10010 1510);
DISPLAY INVISIBLE (10010 1510);
FORCEPROP 1 LASTPIN (10000 1500) BN 10
J 0
(9988 1508);
DISPLAY 0.617021 (9988 1508);
PAINT GREEN (9988 1508);
FORCEPROP 2 LAST CDS_LIB mstr_standard
J 0
(10050 1500);
PAINT ORANGE (10050 1500);
DISPLAY INVISIBLE (10050 1500);
FORCEPROP 1 LAST BODY_TYPE PLUMBING
J 0
(10050 1550);
DISPLAY 0.872340 (10050 1550);
PAINT GREEN (10050 1550);
DISPLAY INVISIBLE (10050 1550);
FORCEPROP 1 LAST HDL_TAP TRUE
J 0
(10375 1375);
DISPLAY 0.872340 (10375 1375);
PAINT ORANGE (10375 1375);
DISPLAY INVISIBLE (10375 1375);
FORCEPROP 1 LAST PATH I330
J 0
(10048 1500);
DISPLAY 0.872340 (10048 1500);
PAINT GREEN (10048 1500);
DISPLAY INVISIBLE (10048 1500);
FORCEADD TAP..1
(10250 1050);
FORCEPROP 3 LASTPIN (10200 1050) SIG_NAME P3E_OCP_CPU0_PE3_C_TXN<8>
J 0
(10210 1060);
DISPLAY 0.659574 (10210 1060);
PAINT MONO (10210 1060);
DISPLAY INVISIBLE (10210 1060);
FORCEPROP 1 LASTPIN (10200 1050) BN 8
J 0
(10188 1058);
DISPLAY 0.617021 (10188 1058);
PAINT GREEN (10188 1058);
FORCEPROP 2 LAST CDS_LIB mstr_standard
J 0
(10250 1050);
PAINT ORANGE (10250 1050);
DISPLAY INVISIBLE (10250 1050);
FORCEPROP 1 LAST BODY_TYPE PLUMBING
J 0
(10250 1100);
DISPLAY 0.872340 (10250 1100);
PAINT GREEN (10250 1100);
DISPLAY INVISIBLE (10250 1100);
FORCEPROP 1 LAST HDL_TAP TRUE
J 0
(10575 925);
DISPLAY 0.872340 (10575 925);
PAINT ORANGE (10575 925);
DISPLAY INVISIBLE (10575 925);
FORCEPROP 1 LAST PATH I331
J 0
(10248 1050);
DISPLAY 0.872340 (10248 1050);
PAINT GREEN (10248 1050);
DISPLAY INVISIBLE (10248 1050);
FORCEADD TAP..1
(10050 1100);
FORCEPROP 3 LASTPIN (10000 1100) SIG_NAME P3E_OCP_CPU0_PE3_C_TXP<8>
J 0
(10010 1110);
DISPLAY 0.659574 (10010 1110);
PAINT MONO (10010 1110);
DISPLAY INVISIBLE (10010 1110);
FORCEPROP 1 LASTPIN (10000 1100) BN 8
J 0
(9988 1108);
DISPLAY 0.617021 (9988 1108);
PAINT GREEN (9988 1108);
FORCEPROP 2 LAST CDS_LIB mstr_standard
J 0
(10050 1100);
PAINT ORANGE (10050 1100);
DISPLAY INVISIBLE (10050 1100);
FORCEPROP 1 LAST BODY_TYPE PLUMBING
J 0
(10050 1150);
DISPLAY 0.872340 (10050 1150);
PAINT GREEN (10050 1150);
DISPLAY INVISIBLE (10050 1150);
FORCEPROP 1 LAST HDL_TAP TRUE
J 0
(10375 975);
DISPLAY 0.872340 (10375 975);
PAINT ORANGE (10375 975);
DISPLAY INVISIBLE (10375 975);
FORCEPROP 1 LAST PATH I332
J 0
(10048 1100);
DISPLAY 0.872340 (10048 1100);
PAINT GREEN (10048 1100);
DISPLAY INVISIBLE (10048 1100);
FORCEADD OFFPAGE..1
R 2
(11025 2575);
FORCEPROP 2 LAST $XR0 106 
J 0
(11211 2575);
DISPLAY 0.638298 (11211 2575);
PAINT MONO (11211 2575);
FORCEPROP 2 LAST PATH I333
J 0
(11200 2650);
DISPLAY 1.021277 (11200 2650);
PAINT ORANGE (11200 2650);
DISPLAY INVISIBLE (11200 2650);
FORCEPROP 1 LAST COMMENT_BODY TRUE
J 2
(10900 2475);
DISPLAY 0.872340 (10900 2475);
PAINT GREEN (10900 2475);
DISPLAY INVISIBLE (10900 2475);
FORCEPROP 1 LAST OFFPAGE TRUE
J 2
(10700 2450);
DISPLAY 0.872340 (10700 2450);
PAINT GREEN (10700 2450);
DISPLAY INVISIBLE (10700 2450);
FORCEPROP 2 LAST CDS_LIB mstr_standard
J 0
(11025 2575);
PAINT ORANGE (11025 2575);
DISPLAY INVISIBLE (11025 2575);
FORCEADD CAP_A..1
(10450 4700);
FORCEPROP 1 LASTPIN (10450 4800) $PN 1
J 0
(10460 4780);
DISPLAY 0.617021 (10460 4780);
PAINT ORANGE (10460 4780);
FORCEPROP 1 LASTPIN (10450 4600) $PN 2
J 0
(10460 4580);
DISPLAY 0.617021 (10460 4580);
PAINT ORANGE (10460 4580);
FORCEPROP 1 LAST MATERIAL X6S
J 0
(10500 4600);
DISPLAY 0.617021 (10500 4600);
PAINT SKYBLUE (10500 4600);
FORCEPROP 1 LAST VOLTAGE 6.3V
J 0
(10500 4700);
DISPLAY 0.617021 (10500 4700);
PAINT SKYBLUE (10500 4700);
FORCEPROP 1 LAST PACK_TYPE 0402V
J 0
(10500 4500);
DISPLAY 0.617021 (10500 4500);
PAINT SKYBLUE (10500 4500);
FORCEPROP 1 LAST TOLERANCE 10%
J 0
(10500 4650);
DISPLAY 0.617021 (10500 4650);
PAINT SKYBLUE (10500 4650);
FORCEPROP 1 LAST VALUE 1.0UF
J 0
(10500 4750);
DISPLAY 0.617021 (10500 4750);
PAINT SKYBLUE (10500 4750);
FORCEPROP 1 LAST PART_NUMBER D97712-004
J 0
(10500 4550);
DISPLAY 0.617021 (10500 4550);
PAINT BLUE (10500 4550);
FORCEPROP 1 LAST LOCATION C1M21
J 0
(10500 4800);
DISPLAY 0.617021 (10500 4800);
PAINT AQUA (10500 4800);
FORCEPROP 2 LAST CDS_LOCATION C1M21
J 0
(10500 4800);
DISPLAY 0.617021 (10500 4800);
PAINT AQUA (10500 4800);
DISPLAY INVISIBLE (10500 4800);
FORCEPROP 2 LAST CDS_LIB dev_discrete
J 0
(10450 4700);
PAINT ORANGE (10450 4700);
DISPLAY INVISIBLE (10450 4700);
FORCEPROP 2 LAST CDS_SEC 1
J 0
(10500 4850);
PAINT ORANGE (10500 4850);
DISPLAY INVISIBLE (10500 4850);
FORCEPROP 2 LAST SEC_TYPE 0402V
J 0
(10500 4900);
DISPLAY 1.021277 (10500 4900);
PAINT ORANGE (10500 4900);
DISPLAY INVISIBLE (10500 4900);
FORCEPROP 2 LAST SEC 1
J 0
(10500 4900);
DISPLAY 0.680851 (10500 4900);
PAINT MONO (10500 4900);
DISPLAY INVISIBLE (10500 4900);
FORCEPROP 1 LAST PATH I334
J 0
(10500 4850);
DISPLAY 0.978723 (10500 4850);
PAINT WHITE (10500 4850);
DISPLAY INVISIBLE (10500 4850);
FORCEPROP 0 LAST ROOM IO_SLOT
J 0
(10500 4900);
DISPLAY 1.021277 (10500 4900);
PAINT ORANGE (10500 4900);
DISPLAY INVISIBLE (10500 4900);
FORCEADD CAP_A..1
(11250 4700);
FORCEPROP 1 LASTPIN (11250 4600) $PN 2
J 0
(11260 4580);
DISPLAY 0.617021 (11260 4580);
PAINT ORANGE (11260 4580);
FORCEPROP 1 LASTPIN (11250 4800) $PN 1
J 0
(11260 4780);
DISPLAY 0.617021 (11260 4780);
PAINT ORANGE (11260 4780);
FORCEPROP 1 LAST MATERIAL X6S
J 0
(11300 4600);
DISPLAY 0.617021 (11300 4600);
PAINT SKYBLUE (11300 4600);
FORCEPROP 1 LAST VOLTAGE 6.3V
J 0
(11300 4700);
DISPLAY 0.617021 (11300 4700);
PAINT SKYBLUE (11300 4700);
FORCEPROP 1 LAST PACK_TYPE 0402V
J 0
(11300 4500);
DISPLAY 0.617021 (11300 4500);
PAINT SKYBLUE (11300 4500);
FORCEPROP 1 LAST TOLERANCE 10%
J 0
(11300 4650);
DISPLAY 0.617021 (11300 4650);
PAINT SKYBLUE (11300 4650);
FORCEPROP 1 LAST VALUE 1.0UF
J 0
(11300 4750);
DISPLAY 0.617021 (11300 4750);
PAINT SKYBLUE (11300 4750);
FORCEPROP 1 LAST PART_NUMBER D97712-004
J 0
(11300 4550);
DISPLAY 0.617021 (11300 4550);
PAINT BLUE (11300 4550);
FORCEPROP 1 LAST LOCATION C1M25
J 0
(11300 4800);
DISPLAY 0.617021 (11300 4800);
PAINT AQUA (11300 4800);
FORCEPROP 2 LAST CDS_SEC 1
J 0
(11300 4850);
PAINT ORANGE (11300 4850);
DISPLAY INVISIBLE (11300 4850);
FORCEPROP 2 LAST CDS_LIB dev_discrete
J 0
(11250 4700);
PAINT ORANGE (11250 4700);
DISPLAY INVISIBLE (11250 4700);
FORCEPROP 2 LAST CDS_LOCATION C1M25
J 0
(11300 4800);
DISPLAY 0.617021 (11300 4800);
PAINT AQUA (11300 4800);
DISPLAY INVISIBLE (11300 4800);
FORCEPROP 2 LAST SEC 1
J 0
(11300 4900);
DISPLAY 0.680851 (11300 4900);
PAINT MONO (11300 4900);
DISPLAY INVISIBLE (11300 4900);
FORCEPROP 2 LAST SEC_TYPE 0402V
J 0
(11300 4900);
DISPLAY 1.021277 (11300 4900);
PAINT ORANGE (11300 4900);
DISPLAY INVISIBLE (11300 4900);
FORCEPROP 1 LAST PATH I335
J 0
(11300 4850);
DISPLAY 0.978723 (11300 4850);
PAINT WHITE (11300 4850);
DISPLAY INVISIBLE (11300 4850);
FORCEPROP 0 LAST ROOM IO_SLOT
J 0
(11300 4900);
DISPLAY 1.021277 (11300 4900);
PAINT ORANGE (11300 4900);
DISPLAY INVISIBLE (11300 4900);
FORCEADD SCONN120_A28699018..1
(8250 2350);
FORCEPROP 1 LAST LOCATION J9B3
J 0
(8150 4100);
DISPLAY 0.617021 (8150 4100);
PAINT AQUA (8150 4100);
FORCEPROP 1 LAST PART_NUMBER A28699-018
J 0
(7900 750);
DISPLAY 0.617021 (7900 750);
PAINT BLUE (7900 750);
FORCEPROP 1 LAST MATERIAL SCONN
J 0
(7900 4050);
DISPLAY 0.617021 (7900 4050);
PAINT SKYBLUE (7900 4050);
FORCEPROP 2 LASTPIN (7850 3850) $PN 1
J 2
(7840 3860);
DISPLAY 0.617021 (7840 3860);
PAINT ORANGE (7840 3860);
FORCEPROP 2 LASTPIN (7850 3800) $PN 3
J 2
(7840 3810);
DISPLAY 0.617021 (7840 3810);
PAINT ORANGE (7840 3810);
FORCEPROP 2 LASTPIN (8650 3850) $PN 2
J 0
(8660 3860);
DISPLAY 0.617021 (8660 3860);
PAINT ORANGE (8660 3860);
FORCEPROP 2 LASTPIN (8650 3800) $PN 4
J 0
(8660 3810);
DISPLAY 0.617021 (8660 3810);
PAINT ORANGE (8660 3810);
FORCEPROP 2 LASTPIN (7850 3750) $PN 5
J 2
(7840 3760);
DISPLAY 0.617021 (7840 3760);
PAINT ORANGE (7840 3760);
FORCEPROP 2 LASTPIN (8650 3750) $PN 6
J 0
(8660 3760);
DISPLAY 0.617021 (8660 3760);
PAINT ORANGE (8660 3760);
FORCEPROP 2 LASTPIN (7850 3700) $PN 7
J 2
(7840 3710);
DISPLAY 0.617021 (7840 3710);
PAINT ORANGE (7840 3710);
FORCEPROP 2 LASTPIN (8650 3700) $PN 8
J 0
(8660 3710);
DISPLAY 0.617021 (8660 3710);
PAINT ORANGE (8660 3710);
FORCEPROP 2 LASTPIN (7850 3650) $PN 9
J 2
(7840 3660);
DISPLAY 0.617021 (7840 3660);
PAINT ORANGE (7840 3660);
FORCEPROP 2 LASTPIN (8650 3650) $PN 10
J 0
(8660 3660);
DISPLAY 0.617021 (8660 3660);
PAINT ORANGE (8660 3660);
FORCEPROP 2 LASTPIN (7850 3600) $PN 11
J 2
(7840 3610);
DISPLAY 0.617021 (7840 3610);
PAINT ORANGE (7840 3610);
FORCEPROP 2 LASTPIN (8650 3600) $PN 12
J 0
(8660 3610);
DISPLAY 0.617021 (8660 3610);
PAINT ORANGE (8660 3610);
FORCEPROP 2 LASTPIN (7850 3550) $PN 13
J 2
(7840 3560);
DISPLAY 0.617021 (7840 3560);
PAINT ORANGE (7840 3560);
FORCEPROP 2 LASTPIN (8650 3550) $PN 14
J 0
(8660 3560);
DISPLAY 0.617021 (8660 3560);
PAINT ORANGE (8660 3560);
FORCEPROP 2 LASTPIN (7850 3500) $PN 15
J 2
(7840 3510);
DISPLAY 0.617021 (7840 3510);
PAINT ORANGE (7840 3510);
FORCEPROP 2 LASTPIN (8650 3500) $PN 16
J 0
(8660 3510);
DISPLAY 0.617021 (8660 3510);
PAINT ORANGE (8660 3510);
FORCEPROP 2 LASTPIN (7850 3450) $PN 17
J 2
(7840 3460);
DISPLAY 0.617021 (7840 3460);
PAINT ORANGE (7840 3460);
FORCEPROP 2 LASTPIN (8650 3450) $PN 18
J 0
(8660 3460);
DISPLAY 0.617021 (8660 3460);
PAINT ORANGE (8660 3460);
FORCEPROP 2 LASTPIN (7850 3400) $PN 19
J 2
(7840 3410);
DISPLAY 0.617021 (7840 3410);
PAINT ORANGE (7840 3410);
FORCEPROP 2 LASTPIN (8650 3400) $PN 20
J 0
(8660 3410);
DISPLAY 0.617021 (8660 3410);
PAINT ORANGE (8660 3410);
FORCEPROP 2 LASTPIN (7850 3350) $PN 21
J 2
(7840 3360);
DISPLAY 0.617021 (7840 3360);
PAINT ORANGE (7840 3360);
FORCEPROP 2 LASTPIN (8650 3350) $PN 22
J 0
(8660 3360);
DISPLAY 0.617021 (8660 3360);
PAINT ORANGE (8660 3360);
FORCEPROP 2 LASTPIN (7850 3300) $PN 23
J 2
(7840 3310);
DISPLAY 0.617021 (7840 3310);
PAINT ORANGE (7840 3310);
FORCEPROP 2 LASTPIN (8650 3300) $PN 24
J 0
(8660 3310);
DISPLAY 0.617021 (8660 3310);
PAINT ORANGE (8660 3310);
FORCEPROP 2 LASTPIN (7850 3250) $PN 25
J 2
(7840 3260);
DISPLAY 0.617021 (7840 3260);
PAINT ORANGE (7840 3260);
FORCEPROP 2 LASTPIN (8650 3250) $PN 26
J 0
(8660 3260);
DISPLAY 0.617021 (8660 3260);
PAINT ORANGE (8660 3260);
FORCEPROP 2 LASTPIN (7850 3200) $PN 27
J 2
(7840 3210);
DISPLAY 0.617021 (7840 3210);
PAINT ORANGE (7840 3210);
FORCEPROP 2 LASTPIN (8650 3200) $PN 28
J 0
(8660 3210);
DISPLAY 0.617021 (8660 3210);
PAINT ORANGE (8660 3210);
FORCEPROP 2 LASTPIN (7850 3150) $PN 29
J 2
(7840 3160);
DISPLAY 0.617021 (7840 3160);
PAINT ORANGE (7840 3160);
FORCEPROP 2 LASTPIN (8650 3150) $PN 30
J 0
(8660 3160);
DISPLAY 0.617021 (8660 3160);
PAINT ORANGE (8660 3160);
FORCEPROP 2 LASTPIN (7850 3100) $PN 31
J 2
(7840 3110);
DISPLAY 0.617021 (7840 3110);
PAINT ORANGE (7840 3110);
FORCEPROP 2 LASTPIN (8650 3100) $PN 32
J 0
(8660 3110);
DISPLAY 0.617021 (8660 3110);
PAINT ORANGE (8660 3110);
FORCEPROP 2 LASTPIN (7850 3050) $PN 33
J 2
(7840 3060);
DISPLAY 0.617021 (7840 3060);
PAINT ORANGE (7840 3060);
FORCEPROP 2 LASTPIN (8650 3050) $PN 34
J 0
(8660 3060);
DISPLAY 0.617021 (8660 3060);
PAINT ORANGE (8660 3060);
FORCEPROP 2 LASTPIN (7850 3000) $PN 35
J 2
(7840 3010);
DISPLAY 0.617021 (7840 3010);
PAINT ORANGE (7840 3010);
FORCEPROP 2 LASTPIN (8650 3000) $PN 36
J 0
(8660 3010);
DISPLAY 0.617021 (8660 3010);
PAINT ORANGE (8660 3010);
FORCEPROP 2 LASTPIN (7850 2950) $PN 37
J 2
(7840 2960);
DISPLAY 0.617021 (7840 2960);
PAINT ORANGE (7840 2960);
FORCEPROP 2 LASTPIN (8650 2950) $PN 38
J 0
(8660 2960);
DISPLAY 0.617021 (8660 2960);
PAINT ORANGE (8660 2960);
FORCEPROP 2 LASTPIN (7850 2900) $PN 39
J 2
(7840 2910);
DISPLAY 0.617021 (7840 2910);
PAINT ORANGE (7840 2910);
FORCEPROP 2 LASTPIN (8650 2900) $PN 40
J 0
(8660 2910);
DISPLAY 0.617021 (8660 2910);
PAINT ORANGE (8660 2910);
FORCEPROP 2 LASTPIN (7850 2850) $PN 41
J 2
(7840 2860);
DISPLAY 0.617021 (7840 2860);
PAINT ORANGE (7840 2860);
FORCEPROP 2 LASTPIN (8650 2850) $PN 42
J 0
(8660 2860);
DISPLAY 0.617021 (8660 2860);
PAINT ORANGE (8660 2860);
FORCEPROP 2 LASTPIN (7850 2800) $PN 43
J 2
(7840 2810);
DISPLAY 0.617021 (7840 2810);
PAINT ORANGE (7840 2810);
FORCEPROP 2 LASTPIN (8650 2800) $PN 44
J 0
(8660 2810);
DISPLAY 0.617021 (8660 2810);
PAINT ORANGE (8660 2810);
FORCEPROP 2 LASTPIN (7850 2750) $PN 45
J 2
(7840 2760);
DISPLAY 0.617021 (7840 2760);
PAINT ORANGE (7840 2760);
FORCEPROP 2 LASTPIN (8650 2750) $PN 46
J 0
(8660 2760);
DISPLAY 0.617021 (8660 2760);
PAINT ORANGE (8660 2760);
FORCEPROP 2 LASTPIN (7850 2700) $PN 47
J 2
(7840 2710);
DISPLAY 0.617021 (7840 2710);
PAINT ORANGE (7840 2710);
FORCEPROP 2 LASTPIN (8650 2700) $PN 48
J 0
(8660 2710);
DISPLAY 0.617021 (8660 2710);
PAINT ORANGE (8660 2710);
FORCEPROP 2 LASTPIN (7850 2650) $PN 49
J 2
(7840 2660);
DISPLAY 0.617021 (7840 2660);
PAINT ORANGE (7840 2660);
FORCEPROP 2 LASTPIN (8650 2650) $PN 50
J 0
(8660 2660);
DISPLAY 0.617021 (8660 2660);
PAINT ORANGE (8660 2660);
FORCEPROP 2 LASTPIN (7850 2600) $PN 51
J 2
(7840 2610);
DISPLAY 0.617021 (7840 2610);
PAINT ORANGE (7840 2610);
FORCEPROP 2 LASTPIN (8650 2600) $PN 52
J 0
(8660 2610);
DISPLAY 0.617021 (8660 2610);
PAINT ORANGE (8660 2610);
FORCEPROP 2 LASTPIN (7850 2550) $PN 53
J 2
(7840 2560);
DISPLAY 0.617021 (7840 2560);
PAINT ORANGE (7840 2560);
FORCEPROP 2 LASTPIN (8650 2550) $PN 54
J 0
(8660 2560);
DISPLAY 0.617021 (8660 2560);
PAINT ORANGE (8660 2560);
FORCEPROP 2 LASTPIN (7850 2500) $PN 55
J 2
(7840 2510);
DISPLAY 0.617021 (7840 2510);
PAINT ORANGE (7840 2510);
FORCEPROP 2 LASTPIN (8650 2500) $PN 56
J 0
(8660 2510);
DISPLAY 0.617021 (8660 2510);
PAINT ORANGE (8660 2510);
FORCEPROP 2 LASTPIN (7850 2450) $PN 57
J 2
(7840 2460);
DISPLAY 0.617021 (7840 2460);
PAINT ORANGE (7840 2460);
FORCEPROP 2 LASTPIN (8650 2450) $PN 58
J 0
(8660 2460);
DISPLAY 0.617021 (8660 2460);
PAINT ORANGE (8660 2460);
FORCEPROP 2 LASTPIN (7850 2400) $PN 59
J 2
(7840 2410);
DISPLAY 0.617021 (7840 2410);
PAINT ORANGE (7840 2410);
FORCEPROP 2 LASTPIN (8650 2400) $PN 60
J 0
(8660 2410);
DISPLAY 0.617021 (8660 2410);
PAINT ORANGE (8660 2410);
FORCEPROP 2 LASTPIN (7850 2350) $PN 61
J 2
(7840 2360);
DISPLAY 0.617021 (7840 2360);
PAINT ORANGE (7840 2360);
FORCEPROP 2 LASTPIN (8650 2350) $PN 62
J 0
(8660 2360);
DISPLAY 0.617021 (8660 2360);
PAINT ORANGE (8660 2360);
FORCEPROP 2 LASTPIN (7850 2300) $PN 63
J 2
(7840 2310);
DISPLAY 0.617021 (7840 2310);
PAINT ORANGE (7840 2310);
FORCEPROP 2 LASTPIN (8650 2300) $PN 64
J 0
(8660 2310);
DISPLAY 0.617021 (8660 2310);
PAINT ORANGE (8660 2310);
FORCEPROP 2 LASTPIN (7850 2250) $PN 65
J 2
(7840 2260);
DISPLAY 0.617021 (7840 2260);
PAINT ORANGE (7840 2260);
FORCEPROP 2 LASTPIN (8650 2250) $PN 66
J 0
(8660 2260);
DISPLAY 0.617021 (8660 2260);
PAINT ORANGE (8660 2260);
FORCEPROP 2 LASTPIN (7850 2200) $PN 67
J 2
(7840 2210);
DISPLAY 0.617021 (7840 2210);
PAINT ORANGE (7840 2210);
FORCEPROP 2 LASTPIN (8650 2200) $PN 68
J 0
(8660 2210);
DISPLAY 0.617021 (8660 2210);
PAINT ORANGE (8660 2210);
FORCEPROP 2 LASTPIN (7850 2150) $PN 69
J 2
(7840 2160);
DISPLAY 0.617021 (7840 2160);
PAINT ORANGE (7840 2160);
FORCEPROP 2 LASTPIN (8650 2150) $PN 70
J 0
(8660 2160);
DISPLAY 0.617021 (8660 2160);
PAINT ORANGE (8660 2160);
FORCEPROP 2 LASTPIN (7850 2100) $PN 71
J 2
(7840 2110);
DISPLAY 0.617021 (7840 2110);
PAINT ORANGE (7840 2110);
FORCEPROP 2 LASTPIN (8650 2100) $PN 72
J 0
(8660 2110);
DISPLAY 0.617021 (8660 2110);
PAINT ORANGE (8660 2110);
FORCEPROP 2 LASTPIN (7850 2050) $PN 73
J 2
(7840 2060);
DISPLAY 0.617021 (7840 2060);
PAINT ORANGE (7840 2060);
FORCEPROP 2 LASTPIN (8650 2050) $PN 74
J 0
(8660 2060);
DISPLAY 0.617021 (8660 2060);
PAINT ORANGE (8660 2060);
FORCEPROP 2 LASTPIN (7850 2000) $PN 75
J 2
(7840 2010);
DISPLAY 0.617021 (7840 2010);
PAINT ORANGE (7840 2010);
FORCEPROP 2 LASTPIN (8650 2000) $PN 76
J 0
(8660 2010);
DISPLAY 0.617021 (8660 2010);
PAINT ORANGE (8660 2010);
FORCEPROP 2 LASTPIN (7850 1950) $PN 77
J 2
(7840 1960);
DISPLAY 0.617021 (7840 1960);
PAINT ORANGE (7840 1960);
FORCEPROP 2 LASTPIN (8650 1950) $PN 78
J 0
(8660 1960);
DISPLAY 0.617021 (8660 1960);
PAINT ORANGE (8660 1960);
FORCEPROP 2 LASTPIN (7850 1900) $PN 79
J 2
(7840 1910);
DISPLAY 0.617021 (7840 1910);
PAINT ORANGE (7840 1910);
FORCEPROP 2 LASTPIN (8650 1900) $PN 80
J 0
(8660 1910);
DISPLAY 0.617021 (8660 1910);
PAINT ORANGE (8660 1910);
FORCEPROP 2 LASTPIN (7850 1850) $PN 81
J 2
(7840 1860);
DISPLAY 0.617021 (7840 1860);
PAINT ORANGE (7840 1860);
FORCEPROP 2 LASTPIN (8650 1850) $PN 82
J 0
(8660 1860);
DISPLAY 0.617021 (8660 1860);
PAINT ORANGE (8660 1860);
FORCEPROP 2 LASTPIN (7850 1800) $PN 83
J 2
(7840 1810);
DISPLAY 0.617021 (7840 1810);
PAINT ORANGE (7840 1810);
FORCEPROP 2 LASTPIN (8650 1800) $PN 84
J 0
(8660 1810);
DISPLAY 0.617021 (8660 1810);
PAINT ORANGE (8660 1810);
FORCEPROP 2 LASTPIN (7850 1750) $PN 85
J 2
(7840 1760);
DISPLAY 0.617021 (7840 1760);
PAINT ORANGE (7840 1760);
FORCEPROP 2 LASTPIN (8650 1750) $PN 86
J 0
(8660 1760);
DISPLAY 0.617021 (8660 1760);
PAINT ORANGE (8660 1760);
FORCEPROP 2 LASTPIN (7850 1700) $PN 87
J 2
(7840 1710);
DISPLAY 0.617021 (7840 1710);
PAINT ORANGE (7840 1710);
FORCEPROP 2 LASTPIN (8650 1700) $PN 88
J 0
(8660 1710);
DISPLAY 0.617021 (8660 1710);
PAINT ORANGE (8660 1710);
FORCEPROP 2 LASTPIN (7850 1650) $PN 89
J 2
(7840 1660);
DISPLAY 0.617021 (7840 1660);
PAINT ORANGE (7840 1660);
FORCEPROP 2 LASTPIN (8650 1650) $PN 90
J 0
(8660 1660);
DISPLAY 0.617021 (8660 1660);
PAINT ORANGE (8660 1660);
FORCEPROP 2 LASTPIN (7850 1600) $PN 91
J 2
(7840 1610);
DISPLAY 0.617021 (7840 1610);
PAINT ORANGE (7840 1610);
FORCEPROP 2 LASTPIN (8650 1600) $PN 92
J 0
(8660 1610);
DISPLAY 0.617021 (8660 1610);
PAINT ORANGE (8660 1610);
FORCEPROP 2 LASTPIN (7850 1550) $PN 93
J 2
(7840 1560);
DISPLAY 0.617021 (7840 1560);
PAINT ORANGE (7840 1560);
FORCEPROP 2 LASTPIN (8650 1550) $PN 94
J 0
(8660 1560);
DISPLAY 0.617021 (8660 1560);
PAINT ORANGE (8660 1560);
FORCEPROP 2 LASTPIN (7850 1500) $PN 95
J 2
(7840 1510);
DISPLAY 0.617021 (7840 1510);
PAINT ORANGE (7840 1510);
FORCEPROP 2 LASTPIN (8650 1500) $PN 96
J 0
(8660 1510);
DISPLAY 0.617021 (8660 1510);
PAINT ORANGE (8660 1510);
FORCEPROP 2 LASTPIN (7850 1450) $PN 97
J 2
(7840 1460);
DISPLAY 0.617021 (7840 1460);
PAINT ORANGE (7840 1460);
FORCEPROP 2 LASTPIN (8650 1450) $PN 98
J 0
(8660 1460);
DISPLAY 0.617021 (8660 1460);
PAINT ORANGE (8660 1460);
FORCEPROP 2 LASTPIN (7850 1400) $PN 99
J 2
(7840 1410);
DISPLAY 0.617021 (7840 1410);
PAINT ORANGE (7840 1410);
FORCEPROP 2 LASTPIN (8650 1400) $PN 100
J 0
(8660 1410);
DISPLAY 0.617021 (8660 1410);
PAINT ORANGE (8660 1410);
FORCEPROP 2 LASTPIN (7850 1350) $PN 101
J 2
(7840 1360);
DISPLAY 0.617021 (7840 1360);
PAINT ORANGE (7840 1360);
FORCEPROP 2 LASTPIN (8650 1350) $PN 102
J 0
(8660 1360);
DISPLAY 0.617021 (8660 1360);
PAINT ORANGE (8660 1360);
FORCEPROP 2 LASTPIN (7850 1300) $PN 103
J 2
(7840 1310);
DISPLAY 0.617021 (7840 1310);
PAINT ORANGE (7840 1310);
FORCEPROP 2 LASTPIN (8650 1300) $PN 104
J 0
(8660 1310);
DISPLAY 0.617021 (8660 1310);
PAINT ORANGE (8660 1310);
FORCEPROP 2 LASTPIN (7850 1250) $PN 105
J 2
(7840 1260);
DISPLAY 0.617021 (7840 1260);
PAINT ORANGE (7840 1260);
FORCEPROP 2 LASTPIN (8650 1250) $PN 106
J 0
(8660 1260);
DISPLAY 0.617021 (8660 1260);
PAINT ORANGE (8660 1260);
FORCEPROP 2 LASTPIN (7850 1200) $PN 107
J 2
(7840 1210);
DISPLAY 0.617021 (7840 1210);
PAINT ORANGE (7840 1210);
FORCEPROP 2 LASTPIN (8650 1200) $PN 108
J 0
(8660 1210);
DISPLAY 0.617021 (8660 1210);
PAINT ORANGE (8660 1210);
FORCEPROP 2 LASTPIN (7850 1150) $PN 109
J 2
(7840 1160);
DISPLAY 0.617021 (7840 1160);
PAINT ORANGE (7840 1160);
FORCEPROP 2 LASTPIN (8650 1150) $PN 110
J 0
(8660 1160);
DISPLAY 0.617021 (8660 1160);
PAINT ORANGE (8660 1160);
FORCEPROP 2 LASTPIN (7850 1100) $PN 111
J 2
(7840 1110);
DISPLAY 0.617021 (7840 1110);
PAINT ORANGE (7840 1110);
FORCEPROP 2 LASTPIN (8650 1100) $PN 112
J 0
(8660 1110);
DISPLAY 0.617021 (8660 1110);
PAINT ORANGE (8660 1110);
FORCEPROP 2 LASTPIN (7850 1050) $PN 113
J 2
(7840 1060);
DISPLAY 0.617021 (7840 1060);
PAINT ORANGE (7840 1060);
FORCEPROP 2 LASTPIN (8650 1050) $PN 114
J 0
(8660 1060);
DISPLAY 0.617021 (8660 1060);
PAINT ORANGE (8660 1060);
FORCEPROP 2 LASTPIN (7850 1000) $PN 115
J 2
(7840 1010);
DISPLAY 0.617021 (7840 1010);
PAINT ORANGE (7840 1010);
FORCEPROP 2 LASTPIN (8650 1000) $PN 116
J 0
(8660 1010);
DISPLAY 0.617021 (8660 1010);
PAINT ORANGE (8660 1010);
FORCEPROP 2 LASTPIN (7850 950) $PN 117
J 2
(7840 960);
DISPLAY 0.617021 (7840 960);
PAINT ORANGE (7840 960);
FORCEPROP 2 LASTPIN (8650 950) $PN 118
J 0
(8660 960);
DISPLAY 0.617021 (8660 960);
PAINT ORANGE (8660 960);
FORCEPROP 2 LASTPIN (7850 900) $PN 119
J 2
(7840 910);
DISPLAY 0.617021 (7840 910);
PAINT ORANGE (7840 910);
FORCEPROP 2 LASTPIN (8650 900) $PN 120
J 0
(8660 910);
DISPLAY 0.617021 (8660 910);
PAINT ORANGE (8660 910);
FORCEPROP 1 LAST PACK_TYPE SM
J 0
(7900 4150);
PAINT SKYBLUE (7900 4150);
DISPLAY INVISIBLE (7900 4150);
FORCEPROP 0 LAST ROOM IO_SLOT
J 0
(8150 4200);
DISPLAY 1.021277 (8150 4200);
PAINT ORANGE (8150 4200);
DISPLAY INVISIBLE (8150 4200);
FORCEPROP 1 LAST PATH I336
J 0
(8200 4050);
PAINT GREEN (8200 4050);
DISPLAY INVISIBLE (8200 4050);
FORCEPROP 2 LAST CDS_LOCATION J9B3
J 0
(8150 4100);
DISPLAY 0.617021 (8150 4100);
PAINT AQUA (8150 4100);
DISPLAY INVISIBLE (8150 4100);
FORCEPROP 2 LAST SEC 1
J 0
(8150 4150);
DISPLAY 0.680851 (8150 4150);
PAINT MONO (8150 4150);
DISPLAY INVISIBLE (8150 4150);
FORCEPROP 2 LAST SEC_TYPE SM
J 0
(8150 4150);
DISPLAY 1.021277 (8150 4150);
PAINT ORANGE (8150 4150);
DISPLAY INVISIBLE (8150 4150);
FORCEPROP 2 LAST CDS_LIB mstr_sconn
J 0
(8250 2350);
PAINT ORANGE (8250 2350);
DISPLAY INVISIBLE (8250 2350);
FORCEADD RES..1
(6700 2750);
FORCEPROP 1 LASTPIN (6800 2750) $PN 2
J 0
(6762 2762);
DISPLAY 0.617021 (6762 2762);
PAINT ORANGE (6762 2762);
FORCEPROP 1 LASTPIN (6600 2750) $PN 1
J 0
(6612 2762);
DISPLAY 0.617021 (6612 2762);
PAINT ORANGE (6612 2762);
FORCEPROP 1 LAST TOLERANCE 5%
J 0
(6750 2700);
DISPLAY 0.617021 (6750 2700);
PAINT SKYBLUE (6750 2700);
FORCEPROP 1 LAST VALUE 0.0
J 2
(6650 2700);
DISPLAY 0.617021 (6650 2700);
PAINT SKYBLUE (6650 2700);
FORCEPROP 1 LAST PART_NUMBER G21497-005
J 0
(6275 2700);
DISPLAY 0.617021 (6275 2700);
PAINT BLUE (6275 2700);
FORCEPROP 1 LAST LOCATION R1M16
J 0
(6625 2825);
DISPLAY 0.617021 (6625 2825);
PAINT AQUA (6625 2825);
FORCEPROP 2 LAST CDS_LIB mstr_discrete
J 0
(6700 2750);
PAINT ORANGE (6700 2750);
DISPLAY INVISIBLE (6700 2750);
FORCEPROP 2 LAST SEC_TYPE 0402
J 0
(6650 2950);
DISPLAY 1.021277 (6650 2950);
PAINT ORANGE (6650 2950);
DISPLAY INVISIBLE (6650 2950);
FORCEPROP 2 LAST SEC 1
J 0
(6650 2950);
DISPLAY 0.680851 (6650 2950);
PAINT MONO (6650 2950);
DISPLAY INVISIBLE (6650 2950);
FORCEPROP 2 LAST CDS_LOCATION R1M16
J 0
(6825 2700);
DISPLAY 0.617021 (6825 2700);
PAINT AQUA (6825 2700);
DISPLAY INVISIBLE (6825 2700);
FORCEPROP 1 LAST PATH I337
J 0
(6650 2900);
DISPLAY 0.978723 (6650 2900);
PAINT WHITE (6650 2900);
DISPLAY INVISIBLE (6650 2900);
FORCEPROP 0 LAST ROOM IO_SLOT
J 0
(6750 2850);
DISPLAY 1.021277 (6750 2850);
PAINT ORANGE (6750 2850);
DISPLAY INVISIBLE (6750 2850);
FORCEPROP 1 LAST WATTAGE 1/16W
J 2
(6675 2600);
DISPLAY 0.617021 (6675 2600);
PAINT SKYBLUE (6675 2600);
DISPLAY INVISIBLE (6675 2600);
FORCEPROP 1 LAST MATERIAL CHIP
J 0
(6700 2600);
DISPLAY 0.617021 (6700 2600);
PAINT SKYBLUE (6700 2600);
DISPLAY INVISIBLE (6700 2600);
FORCEPROP 1 LAST PACK_TYPE 0402
J 0
(6950 2600);
DISPLAY 0.617021 (6950 2600);
PAINT SKYBLUE (6950 2600);
DISPLAY INVISIBLE (6950 2600);
FORCEADD RES..1
(6375 2800);
FORCEPROP 1 LASTPIN (6475 2800) $PN 2
J 0
(6437 2812);
DISPLAY 0.617021 (6437 2812);
PAINT ORANGE (6437 2812);
FORCEPROP 1 LASTPIN (6275 2800) $PN 1
J 0
(6287 2812);
DISPLAY 0.617021 (6287 2812);
PAINT ORANGE (6287 2812);
FORCEPROP 1 LAST TOLERANCE 5%
J 0
(6425 2750);
DISPLAY 0.617021 (6425 2750);
PAINT SKYBLUE (6425 2750);
FORCEPROP 1 LAST VALUE 0.0
J 2
(6325 2750);
DISPLAY 0.617021 (6325 2750);
PAINT SKYBLUE (6325 2750);
FORCEPROP 1 LAST PART_NUMBER G21497-005
J 0
(6050 2800);
DISPLAY 0.617021 (6050 2800);
PAINT BLUE (6050 2800);
FORCEPROP 1 LAST LOCATION R1M17
J 0
(6325 2850);
DISPLAY 0.617021 (6325 2850);
PAINT AQUA (6325 2850);
FORCEPROP 2 LAST SEC_TYPE 0402
J 0
(6325 3000);
DISPLAY 1.021277 (6325 3000);
PAINT ORANGE (6325 3000);
DISPLAY INVISIBLE (6325 3000);
FORCEPROP 2 LAST CDS_LIB mstr_discrete
J 0
(6375 2800);
PAINT ORANGE (6375 2800);
DISPLAY INVISIBLE (6375 2800);
FORCEPROP 2 LAST SEC 1
J 0
(6325 3000);
DISPLAY 0.680851 (6325 3000);
PAINT MONO (6325 3000);
DISPLAY INVISIBLE (6325 3000);
FORCEPROP 2 LAST CDS_LOCATION R1M17
J 0
(6475 2800);
DISPLAY 0.617021 (6475 2800);
PAINT AQUA (6475 2800);
DISPLAY INVISIBLE (6475 2800);
FORCEPROP 1 LAST PATH I338
J 0
(6325 2950);
DISPLAY 0.978723 (6325 2950);
PAINT WHITE (6325 2950);
DISPLAY INVISIBLE (6325 2950);
FORCEPROP 0 LAST ROOM IO_SLOT
J 0
(6425 2900);
DISPLAY 1.021277 (6425 2900);
PAINT ORANGE (6425 2900);
DISPLAY INVISIBLE (6425 2900);
FORCEPROP 1 LAST WATTAGE 1/16W
J 2
(6350 2650);
DISPLAY 0.617021 (6350 2650);
PAINT SKYBLUE (6350 2650);
DISPLAY INVISIBLE (6350 2650);
FORCEPROP 1 LAST MATERIAL CHIP
J 0
(6375 2650);
DISPLAY 0.617021 (6375 2650);
PAINT SKYBLUE (6375 2650);
DISPLAY INVISIBLE (6375 2650);
FORCEPROP 1 LAST PACK_TYPE 0402
J 0
(6625 2650);
DISPLAY 0.617021 (6625 2650);
PAINT SKYBLUE (6625 2650);
DISPLAY INVISIBLE (6625 2650);
FORCEADD RES..1
(6375 3200);
FORCEPROP 1 LASTPIN (6475 3200) $PN 2
J 0
(6437 3212);
DISPLAY 0.617021 (6437 3212);
PAINT ORANGE (6437 3212);
FORCEPROP 1 LASTPIN (6275 3200) $PN 1
J 0
(6287 3212);
DISPLAY 0.617021 (6287 3212);
PAINT ORANGE (6287 3212);
FORCEPROP 1 LAST TOLERANCE 5%
J 0
(6425 3150);
DISPLAY 0.617021 (6425 3150);
PAINT SKYBLUE (6425 3150);
FORCEPROP 1 LAST VALUE 0.0
J 2
(6325 3150);
DISPLAY 0.617021 (6325 3150);
PAINT SKYBLUE (6325 3150);
FORCEPROP 1 LAST PART_NUMBER G21497-005
J 0
(6050 3200);
DISPLAY 0.617021 (6050 3200);
PAINT BLUE (6050 3200);
FORCEPROP 1 LAST LOCATION R1M15
J 0
(6300 3275);
DISPLAY 0.617021 (6300 3275);
PAINT AQUA (6300 3275);
FORCEPROP 2 LAST SEC_TYPE 0402
J 0
(6325 3400);
DISPLAY 1.021277 (6325 3400);
PAINT ORANGE (6325 3400);
DISPLAY INVISIBLE (6325 3400);
FORCEPROP 2 LAST CDS_LIB mstr_discrete
J 0
(6375 3200);
PAINT ORANGE (6375 3200);
DISPLAY INVISIBLE (6375 3200);
FORCEPROP 2 LAST SEC 1
J 0
(6325 3400);
DISPLAY 0.680851 (6325 3400);
PAINT MONO (6325 3400);
DISPLAY INVISIBLE (6325 3400);
FORCEPROP 2 LAST CDS_LOCATION R1M15
J 0
(6500 3200);
DISPLAY 0.617021 (6500 3200);
PAINT AQUA (6500 3200);
DISPLAY INVISIBLE (6500 3200);
FORCEPROP 1 LAST PATH I339
J 0
(6325 3350);
DISPLAY 0.978723 (6325 3350);
PAINT WHITE (6325 3350);
DISPLAY INVISIBLE (6325 3350);
FORCEPROP 0 LAST ROOM IO_SLOT
J 0
(6425 3300);
DISPLAY 1.021277 (6425 3300);
PAINT ORANGE (6425 3300);
DISPLAY INVISIBLE (6425 3300);
FORCEPROP 1 LAST WATTAGE 1/16W
J 2
(6350 3050);
DISPLAY 0.617021 (6350 3050);
PAINT SKYBLUE (6350 3050);
DISPLAY INVISIBLE (6350 3050);
FORCEPROP 1 LAST MATERIAL CHIP
J 0
(6375 3050);
DISPLAY 0.617021 (6375 3050);
PAINT SKYBLUE (6375 3050);
DISPLAY INVISIBLE (6375 3050);
FORCEPROP 1 LAST PACK_TYPE 0402
J 0
(6625 3050);
DISPLAY 0.617021 (6625 3050);
PAINT SKYBLUE (6625 3050);
DISPLAY INVISIBLE (6625 3050);
FORCEADD RES..1
(10250 3000);
FORCEPROP 1 LASTPIN (10350 3000) $PN 2
J 0
(10312 3012);
DISPLAY 0.617021 (10312 3012);
PAINT ORANGE (10312 3012);
FORCEPROP 1 LASTPIN (10150 3000) $PN 1
J 0
(10162 3012);
DISPLAY 0.617021 (10162 3012);
PAINT ORANGE (10162 3012);
FORCEPROP 1 LAST TOLERANCE 5%
J 0
(10300 2950);
DISPLAY 0.617021 (10300 2950);
PAINT SKYBLUE (10300 2950);
FORCEPROP 1 LAST VALUE 0.0
J 2
(10200 2950);
DISPLAY 0.617021 (10200 2950);
PAINT SKYBLUE (10200 2950);
FORCEPROP 1 LAST PART_NUMBER G21497-005
J 0
(9825 2950);
DISPLAY 0.617021 (9825 2950);
PAINT BLUE (9825 2950);
FORCEPROP 1 LAST LOCATION R1M18
J 0
(10175 3050);
DISPLAY 0.617021 (10175 3050);
PAINT AQUA (10175 3050);
FORCEPROP 2 LAST SEC_TYPE 0402
J 0
(10200 3200);
DISPLAY 1.021277 (10200 3200);
PAINT ORANGE (10200 3200);
DISPLAY INVISIBLE (10200 3200);
FORCEPROP 2 LAST CDS_LIB mstr_discrete
J 0
(10250 3000);
PAINT ORANGE (10250 3000);
DISPLAY INVISIBLE (10250 3000);
FORCEPROP 2 LAST SEC 1
J 0
(10200 3200);
DISPLAY 0.680851 (10200 3200);
PAINT MONO (10200 3200);
DISPLAY INVISIBLE (10200 3200);
FORCEPROP 2 LAST CDS_LOCATION R1M18
J 0
(10425 2950);
DISPLAY 0.617021 (10425 2950);
PAINT AQUA (10425 2950);
DISPLAY INVISIBLE (10425 2950);
FORCEPROP 1 LAST PATH I340
J 0
(10200 3150);
DISPLAY 0.978723 (10200 3150);
PAINT WHITE (10200 3150);
DISPLAY INVISIBLE (10200 3150);
FORCEPROP 0 LAST ROOM IO_SLOT
J 0
(10300 3100);
DISPLAY 1.021277 (10300 3100);
PAINT ORANGE (10300 3100);
DISPLAY INVISIBLE (10300 3100);
FORCEPROP 1 LAST WATTAGE 1/16W
J 2
(10225 2850);
DISPLAY 0.617021 (10225 2850);
PAINT SKYBLUE (10225 2850);
DISPLAY INVISIBLE (10225 2850);
FORCEPROP 1 LAST MATERIAL CHIP
J 0
(10250 2850);
DISPLAY 0.617021 (10250 2850);
PAINT SKYBLUE (10250 2850);
DISPLAY INVISIBLE (10250 2850);
FORCEPROP 1 LAST PACK_TYPE 0402
J 0
(10500 2850);
DISPLAY 0.617021 (10500 2850);
PAINT SKYBLUE (10500 2850);
DISPLAY INVISIBLE (10500 2850);
FORCEADD OFFPAGE..5
(5150 3200);
FORCEPROP 2 LAST $XR0 147 
J 0
(4895 3200);
DISPLAY 0.638298 (4895 3200);
PAINT MONO (4895 3200);
FORCEPROP 2 LAST PATH I341
J 0
(5200 3275);
DISPLAY 1.021277 (5200 3275);
PAINT ORANGE (5200 3275);
DISPLAY INVISIBLE (5200 3275);
FORCEPROP 1 LAST COMMENT_BODY TRUE
J 0
(5250 3125);
DISPLAY 0.872340 (5250 3125);
PAINT GREEN (5250 3125);
DISPLAY INVISIBLE (5250 3125);
FORCEPROP 1 LAST OFFPAGE TRUE
J 0
(5475 3075);
DISPLAY 0.872340 (5475 3075);
PAINT GREEN (5475 3075);
DISPLAY INVISIBLE (5475 3075);
FORCEPROP 2 LAST CDS_LIB mstr_standard
J 0
(5150 3200);
PAINT ORANGE (5150 3200);
DISPLAY INVISIBLE (5150 3200);
FORCEADD OFFPAGE..5
(5150 2800);
FORCEPROP 2 LAST $XR0 147 
J 0
(4895 2800);
DISPLAY 0.638298 (4895 2800);
PAINT MONO (4895 2800);
FORCEPROP 2 LAST PATH I342
J 0
(5200 2875);
DISPLAY 1.021277 (5200 2875);
PAINT ORANGE (5200 2875);
DISPLAY INVISIBLE (5200 2875);
FORCEPROP 1 LAST COMMENT_BODY TRUE
J 0
(5250 2725);
DISPLAY 0.872340 (5250 2725);
PAINT GREEN (5250 2725);
DISPLAY INVISIBLE (5250 2725);
FORCEPROP 1 LAST OFFPAGE TRUE
J 0
(5475 2675);
DISPLAY 0.872340 (5475 2675);
PAINT GREEN (5475 2675);
DISPLAY INVISIBLE (5475 2675);
FORCEPROP 2 LAST CDS_LIB mstr_standard
J 0
(5150 2800);
PAINT ORANGE (5150 2800);
DISPLAY INVISIBLE (5150 2800);
FORCEADD OFFPAGE..5
(5150 2750);
FORCEPROP 2 LAST $XR0 147 
J 0
(4895 2750);
DISPLAY 0.638298 (4895 2750);
PAINT MONO (4895 2750);
FORCEPROP 2 LAST PATH I343
J 0
(5200 2825);
DISPLAY 1.021277 (5200 2825);
PAINT ORANGE (5200 2825);
DISPLAY INVISIBLE (5200 2825);
FORCEPROP 1 LAST COMMENT_BODY TRUE
J 0
(5250 2675);
DISPLAY 0.872340 (5250 2675);
PAINT GREEN (5250 2675);
DISPLAY INVISIBLE (5250 2675);
FORCEPROP 1 LAST OFFPAGE TRUE
J 0
(5475 2625);
DISPLAY 0.872340 (5475 2625);
PAINT GREEN (5475 2625);
DISPLAY INVISIBLE (5475 2625);
FORCEPROP 2 LAST CDS_LIB mstr_standard
J 0
(5150 2750);
PAINT ORANGE (5150 2750);
DISPLAY INVISIBLE (5150 2750);
FORCEADD OFFPAGE..2
(11100 3000);
FORCEPROP 2 LAST $XR0 147 
J 0
(11289 3000);
DISPLAY 0.638298 (11289 3000);
PAINT MONO (11289 3000);
FORCEPROP 2 LAST PATH I344
J 0
(11150 3075);
DISPLAY 1.021277 (11150 3075);
PAINT ORANGE (11150 3075);
DISPLAY INVISIBLE (11150 3075);
FORCEPROP 1 LAST COMMENT_BODY TRUE
J 0
(11055 2905);
DISPLAY 0.872340 (11055 2905);
PAINT GREEN (11055 2905);
DISPLAY INVISIBLE (11055 2905);
FORCEPROP 1 LAST OFFPAGE TRUE
J 0
(11425 2875);
DISPLAY 0.872340 (11425 2875);
PAINT GREEN (11425 2875);
DISPLAY INVISIBLE (11425 2875);
FORCEPROP 2 LAST CDS_LIB mstr_standard
J 0
(11100 3000);
PAINT ORANGE (11100 3000);
DISPLAY INVISIBLE (11100 3000);
FORCEADD CAP_A..1
(10050 3950);
FORCEPROP 1 LAST LOCATION C9B10
J 0
(10100 4050);
DISPLAY 0.617021 (10100 4050);
PAINT AQUA (10100 4050);
FORCEPROP 1 LAST MATERIAL X7R
J 0
(10100 3850);
DISPLAY 0.617021 (10100 3850);
PAINT SKYBLUE (10100 3850);
FORCEPROP 1 LASTPIN (10050 3850) $PN 2
J 0
(10060 3830);
DISPLAY 0.617021 (10060 3830);
PAINT ORANGE (10060 3830);
FORCEPROP 1 LASTPIN (10050 4050) $PN 1
J 0
(10060 4030);
DISPLAY 0.617021 (10060 4030);
PAINT ORANGE (10060 4030);
FORCEPROP 1 LAST VOLTAGE 16V
J 0
(10100 3950);
DISPLAY 0.617021 (10100 3950);
PAINT SKYBLUE (10100 3950);
FORCEPROP 1 LAST PACK_TYPE 0402V
J 0
(10100 3750);
DISPLAY 0.617021 (10100 3750);
PAINT SKYBLUE (10100 3750);
FORCEPROP 1 LAST TOLERANCE 10%
J 0
(10100 3900);
DISPLAY 0.617021 (10100 3900);
PAINT SKYBLUE (10100 3900);
FORCEPROP 1 LAST VALUE 0.1UF
J 0
(10100 4000);
DISPLAY 0.617021 (10100 4000);
PAINT SKYBLUE (10100 4000);
FORCEPROP 1 LAST PART_NUMBER A36096-030
J 0
(10100 3800);
DISPLAY 0.617021 (10100 3800);
PAINT BLUE (10100 3800);
FORCEPROP 1 LAST PATH I345
J 0
(10100 4100);
DISPLAY 0.978723 (10100 4100);
PAINT WHITE (10100 4100);
DISPLAY INVISIBLE (10100 4100);
FORCEPROP 2 LAST CDS_LIB dev_discrete
J 0
(10050 3950);
PAINT ORANGE (10050 3950);
DISPLAY INVISIBLE (10050 3950);
FORCEPROP 2 LAST SEC 1
J 0
(10100 4150);
DISPLAY 0.680851 (10100 4150);
PAINT MONO (10100 4150);
DISPLAY INVISIBLE (10100 4150);
FORCEPROP 2 LAST SEC_TYPE 0402V
J 0
(10100 4150);
DISPLAY 1.021277 (10100 4150);
PAINT ORANGE (10100 4150);
DISPLAY INVISIBLE (10100 4150);
FORCEPROP 0 LAST ROOM IO_SLOT
J 0
(10100 4150);
DISPLAY 1.021277 (10100 4150);
PAINT ORANGE (10100 4150);
DISPLAY INVISIBLE (10100 4150);
FORCEADD GND..1
(10050 3550);
FORCEPROP 3 LASTPIN (10050 3600) SIG_NAME GND\g
J 0
(10060 3610);
DISPLAY 0.659574 (10060 3610);
PAINT MONO (10060 3610);
DISPLAY INVISIBLE (10060 3610);
FORCEPROP 1 LAST SIZE 1B
J 0
(10125 3500);
DISPLAY 0.872340 (10125 3500);
PAINT AQUA (10125 3500);
DISPLAY INVISIBLE (10125 3500);
FORCEPROP 1 LAST BODY_TYPE PLUMBING
J 0
(10005 3507);
DISPLAY 0.340426 (10005 3507);
PAINT GREEN (10005 3507);
DISPLAY INVISIBLE (10005 3507);
FORCEPROP 1 LAST PATH I346
J 0
(10125 3550);
DISPLAY 0.872340 (10125 3550);
PAINT AQUA (10125 3550);
DISPLAY INVISIBLE (10125 3550);
FORCEPROP 2 LAST CDS_LIB mstr_symbols
J 0
(10050 3550);
PAINT ORANGE (10050 3550);
DISPLAY INVISIBLE (10050 3550);
FORCEPROP 1 LAST HDL_POWER GND
J 0
(10050 3700);
DISPLAY 0.872340 (10050 3700);
PAINT GREEN (10050 3700);
DISPLAY INVISIBLE (10050 3700);
FORCEPROP 1 LAST VOLTAGE 0
J 0
(10050 3550);
PAINT SKYBLUE (10050 3550);
DISPLAY INVISIBLE (10050 3550);
FORCEADD CAP_A..1
(9650 3950);
FORCEPROP 1 LAST LOCATION C9B9
J 0
(9700 4050);
DISPLAY 0.617021 (9700 4050);
PAINT AQUA (9700 4050);
FORCEPROP 1 LAST TOLERANCE 10%
J 0
(9700 3900);
DISPLAY 0.617021 (9700 3900);
PAINT SKYBLUE (9700 3900);
FORCEPROP 1 LAST MATERIAL X6S
J 0
(9700 3850);
DISPLAY 0.617021 (9700 3850);
PAINT SKYBLUE (9700 3850);
FORCEPROP 1 LAST PART_NUMBER D97712-004
J 0
(9700 3800);
DISPLAY 0.617021 (9700 3800);
PAINT BLUE (9700 3800);
FORCEPROP 1 LAST VOLTAGE 6.3V
J 0
(9700 3950);
DISPLAY 0.617021 (9700 3950);
PAINT SKYBLUE (9700 3950);
FORCEPROP 1 LAST VALUE 1.0UF
J 0
(9700 4000);
DISPLAY 0.617021 (9700 4000);
PAINT SKYBLUE (9700 4000);
FORCEPROP 1 LAST PACK_TYPE 0402V
J 0
(9700 3750);
DISPLAY 0.617021 (9700 3750);
PAINT SKYBLUE (9700 3750);
FORCEPROP 1 LASTPIN (9650 3850) $PN 2
J 0
(9660 3830);
DISPLAY 0.617021 (9660 3830);
PAINT ORANGE (9660 3830);
FORCEPROP 1 LASTPIN (9650 4050) $PN 1
J 0
(9660 4030);
DISPLAY 0.617021 (9660 4030);
PAINT ORANGE (9660 4030);
FORCEPROP 1 LAST PATH I347
J 0
(9700 4100);
DISPLAY 0.978723 (9700 4100);
PAINT WHITE (9700 4100);
DISPLAY INVISIBLE (9700 4100);
FORCEPROP 2 LAST CDS_LIB dev_discrete
J 0
(9650 3950);
PAINT ORANGE (9650 3950);
DISPLAY INVISIBLE (9650 3950);
FORCEPROP 2 LAST SEC_TYPE 0402V
J 0
(9700 4150);
DISPLAY 1.021277 (9700 4150);
PAINT ORANGE (9700 4150);
DISPLAY INVISIBLE (9700 4150);
FORCEPROP 2 LAST SEC 1
J 0
(9700 4150);
DISPLAY 0.680851 (9700 4150);
PAINT MONO (9700 4150);
DISPLAY INVISIBLE (9700 4150);
FORCEPROP 0 LAST ROOM IO_SLOT
J 0
(9700 4150);
DISPLAY 1.021277 (9700 4150);
PAINT ORANGE (9700 4150);
DISPLAY INVISIBLE (9700 4150);
FORCEADD P5V_STBY..1
(9650 4225);
FORCEPROP 3 LASTPIN (9650 4175) SIG_NAME P5V_STBY\g
J 0
(9660 4185);
DISPLAY 0.659574 (9660 4185);
PAINT MONO (9660 4185);
DISPLAY INVISIBLE (9660 4185);
FORCEPROP 1 LAST SIZE 1B
J 0
(9695 4247);
DISPLAY 0.340426 (9695 4247);
PAINT GREEN (9695 4247);
DISPLAY INVISIBLE (9695 4247);
FORCEPROP 1 LAST BODY_TYPE PLUMBING
J 0
(9605 4182);
DISPLAY 0.340426 (9605 4182);
PAINT GREEN (9605 4182);
DISPLAY INVISIBLE (9605 4182);
FORCEPROP 1 LAST PATH I348
J 0
(9695 4227);
DISPLAY 0.340426 (9695 4227);
PAINT GREEN (9695 4227);
DISPLAY INVISIBLE (9695 4227);
FORCEPROP 2 LAST CDS_LIB mstr_symbols
J 0
(9650 4225);
PAINT ORANGE (9650 4225);
DISPLAY INVISIBLE (9650 4225);
FORCEPROP 1 LAST HDL_POWER P5V_STBY
J 0
(9350 4100);
DISPLAY 0.872340 (9350 4100);
PAINT ORANGE (9350 4100);
DISPLAY INVISIBLE (9350 4100);
FORCEPROP 1 LAST VOLTAGE 5.0V
J 0
(9605 4182);
DISPLAY 0.340426 (9605 4182);
PAINT SKYBLUE (9605 4182);
DISPLAY INVISIBLE (9605 4182);
FORCEADD CAP..1
(10850 3950);
FORCEPROP 1 LASTPIN (10850 3850) $PN 2
J 0
(10860 3830);
DISPLAY 0.617021 (10860 3830);
PAINT ORANGE (10860 3830);
FORCEPROP 1 LASTPIN (10850 4050) $PN 1
J 0
(10860 4030);
DISPLAY 0.617021 (10860 4030);
PAINT ORANGE (10860 4030);
FORCEPROP 1 LAST MATERIAL X6S
J 0
(10900 3850);
DISPLAY 0.617021 (10900 3850);
PAINT SKYBLUE (10900 3850);
FORCEPROP 1 LAST VOLTAGE 16V
J 0
(10900 3950);
DISPLAY 0.617021 (10900 3950);
PAINT SKYBLUE (10900 3950);
FORCEPROP 1 LAST PACK_TYPE 0805
J 0
(10900 3750);
DISPLAY 0.617021 (10900 3750);
PAINT SKYBLUE (10900 3750);
FORCEPROP 1 LAST TOLERANCE 10%
J 0
(10900 3900);
DISPLAY 0.617021 (10900 3900);
PAINT SKYBLUE (10900 3900);
FORCEPROP 1 LAST VALUE 10UF
J 0
(10900 4000);
DISPLAY 0.617021 (10900 4000);
PAINT SKYBLUE (10900 4000);
FORCEPROP 1 LAST PART_NUMBER C95333-007
J 0
(10900 3800);
DISPLAY 0.617021 (10900 3800);
PAINT BLUE (10900 3800);
FORCEPROP 1 LAST LOCATION C1M26
J 0
(10900 4050);
DISPLAY 0.617021 (10900 4050);
PAINT AQUA (10900 4050);
FORCEPROP 2 LAST SEC_TYPE 0805
J 0
(10900 4150);
DISPLAY 1.021277 (10900 4150);
PAINT ORANGE (10900 4150);
DISPLAY INVISIBLE (10900 4150);
FORCEPROP 2 LAST CDS_LIB mstr_discrete
J 0
(10850 3950);
PAINT ORANGE (10850 3950);
DISPLAY INVISIBLE (10850 3950);
FORCEPROP 2 LAST SEC 1
J 0
(10900 4150);
DISPLAY 0.680851 (10900 4150);
PAINT MONO (10900 4150);
DISPLAY INVISIBLE (10900 4150);
FORCEPROP 2 LAST CDS_LOCATION C1M26
J 0
(10900 4050);
DISPLAY 0.617021 (10900 4050);
PAINT AQUA (10900 4050);
DISPLAY INVISIBLE (10900 4050);
FORCEPROP 1 LAST PATH I6
J 0
(10900 4100);
DISPLAY 0.978723 (10900 4100);
PAINT WHITE (10900 4100);
DISPLAY INVISIBLE (10900 4100);
FORCEPROP 0 LAST ROOM IO_SLOT
J 0
(10900 4150);
DISPLAY 1.021277 (10900 4150);
PAINT ORANGE (10900 4150);
DISPLAY INVISIBLE (10900 4150);
FORCEADD CAP_A..1
(11225 3950);
FORCEPROP 1 LASTPIN (11225 4050) $PN 1
J 0
(11235 4030);
DISPLAY 0.617021 (11235 4030);
PAINT ORANGE (11235 4030);
FORCEPROP 1 LASTPIN (11225 3850) $PN 2
J 0
(11235 3830);
DISPLAY 0.617021 (11235 3830);
PAINT ORANGE (11235 3830);
FORCEPROP 1 LAST MATERIAL X7R
J 0
(11275 3850);
DISPLAY 0.617021 (11275 3850);
PAINT SKYBLUE (11275 3850);
FORCEPROP 1 LAST VOLTAGE 16V
J 0
(11275 3950);
DISPLAY 0.617021 (11275 3950);
PAINT SKYBLUE (11275 3950);
FORCEPROP 1 LAST PACK_TYPE 0402V
J 0
(11275 3750);
DISPLAY 0.617021 (11275 3750);
PAINT SKYBLUE (11275 3750);
FORCEPROP 1 LAST TOLERANCE 10%
J 0
(11275 3900);
DISPLAY 0.617021 (11275 3900);
PAINT SKYBLUE (11275 3900);
FORCEPROP 1 LAST VALUE 0.1UF
J 0
(11275 4000);
DISPLAY 0.617021 (11275 4000);
PAINT SKYBLUE (11275 4000);
FORCEPROP 1 LAST PART_NUMBER A36096-030
J 0
(11275 3800);
DISPLAY 0.617021 (11275 3800);
PAINT BLUE (11275 3800);
FORCEPROP 1 LAST LOCATION C1M23
J 0
(11275 4050);
DISPLAY 0.617021 (11275 4050);
PAINT AQUA (11275 4050);
FORCEPROP 1 LAST PATH I7
J 0
(11275 4100);
DISPLAY 0.978723 (11275 4100);
PAINT WHITE (11275 4100);
DISPLAY INVISIBLE (11275 4100);
FORCEPROP 2 LAST CDS_LOCATION C1M23
J 0
(11275 4050);
DISPLAY 0.617021 (11275 4050);
PAINT AQUA (11275 4050);
DISPLAY INVISIBLE (11275 4050);
FORCEPROP 2 LAST CDS_LIB dev_discrete
J 0
(11225 3950);
PAINT ORANGE (11225 3950);
DISPLAY INVISIBLE (11225 3950);
FORCEPROP 2 LAST CDS_SEC 1
J 0
(11275 4100);
PAINT ORANGE (11275 4100);
DISPLAY INVISIBLE (11275 4100);
FORCEPROP 2 LAST SEC_TYPE 0402V
J 0
(11275 4150);
DISPLAY 1.021277 (11275 4150);
PAINT ORANGE (11275 4150);
DISPLAY INVISIBLE (11275 4150);
FORCEPROP 2 LAST SEC 1
J 0
(11275 4150);
DISPLAY 0.680851 (11275 4150);
PAINT MONO (11275 4150);
DISPLAY INVISIBLE (11275 4150);
FORCEPROP 0 LAST ROOM IO_SLOT
J 0
(11275 4150);
DISPLAY 1.021277 (11275 4150);
PAINT ORANGE (11275 4150);
DISPLAY INVISIBLE (11275 4150);
FORCEADD CAP_A..1
(11650 3950);
FORCEPROP 1 LASTPIN (11650 3850) $PN 2
J 0
(11660 3830);
DISPLAY 0.617021 (11660 3830);
PAINT ORANGE (11660 3830);
FORCEPROP 1 LASTPIN (11650 4050) $PN 1
J 0
(11660 4030);
DISPLAY 0.617021 (11660 4030);
PAINT ORANGE (11660 4030);
FORCEPROP 1 LAST MATERIAL X7R
J 0
(11700 3850);
DISPLAY 0.617021 (11700 3850);
PAINT SKYBLUE (11700 3850);
FORCEPROP 1 LAST VOLTAGE 16V
J 0
(11700 3950);
DISPLAY 0.617021 (11700 3950);
PAINT SKYBLUE (11700 3950);
FORCEPROP 1 LAST PACK_TYPE 0402V
J 0
(11700 3750);
DISPLAY 0.617021 (11700 3750);
PAINT SKYBLUE (11700 3750);
FORCEPROP 1 LAST TOLERANCE 10%
J 0
(11700 3900);
DISPLAY 0.617021 (11700 3900);
PAINT SKYBLUE (11700 3900);
FORCEPROP 1 LAST VALUE 0.1UF
J 0
(11700 4000);
DISPLAY 0.617021 (11700 4000);
PAINT SKYBLUE (11700 4000);
FORCEPROP 1 LAST PART_NUMBER A36096-030
J 0
(11700 3800);
DISPLAY 0.617021 (11700 3800);
PAINT BLUE (11700 3800);
FORCEPROP 1 LAST LOCATION C1M22
J 0
(11700 4050);
DISPLAY 0.617021 (11700 4050);
PAINT AQUA (11700 4050);
FORCEPROP 1 LAST PATH I8
J 0
(11700 4100);
DISPLAY 0.978723 (11700 4100);
PAINT WHITE (11700 4100);
DISPLAY INVISIBLE (11700 4100);
FORCEPROP 2 LAST CDS_LOCATION C1M22
J 0
(11700 4050);
DISPLAY 0.617021 (11700 4050);
PAINT AQUA (11700 4050);
DISPLAY INVISIBLE (11700 4050);
FORCEPROP 2 LAST CDS_LIB dev_discrete
J 0
(11650 3950);
PAINT ORANGE (11650 3950);
DISPLAY INVISIBLE (11650 3950);
FORCEPROP 2 LAST CDS_SEC 1
J 0
(11700 4100);
PAINT ORANGE (11700 4100);
DISPLAY INVISIBLE (11700 4100);
FORCEPROP 2 LAST SEC_TYPE 0402V
J 0
(11700 4150);
DISPLAY 1.021277 (11700 4150);
PAINT ORANGE (11700 4150);
DISPLAY INVISIBLE (11700 4150);
FORCEPROP 2 LAST SEC 1
J 0
(11700 4150);
DISPLAY 0.680851 (11700 4150);
PAINT MONO (11700 4150);
DISPLAY INVISIBLE (11700 4150);
FORCEPROP 0 LAST ROOM IO_SLOT
J 0
(11700 4150);
DISPLAY 1.021277 (11700 4150);
PAINT ORANGE (11700 4150);
DISPLAY INVISIBLE (11700 4150);
FORCEADD GND..1
(10850 4275);
FORCEPROP 3 LASTPIN (10850 4325) SIG_NAME GND\g
J 0
(10860 4335);
DISPLAY 0.659574 (10860 4335);
PAINT MONO (10860 4335);
DISPLAY INVISIBLE (10860 4335);
FORCEPROP 1 LAST SIZE 1B
J 0
(10925 4225);
DISPLAY 0.872340 (10925 4225);
PAINT AQUA (10925 4225);
DISPLAY INVISIBLE (10925 4225);
FORCEPROP 2 LAST CDS_LIB mstr_symbols
J 0
(10850 4275);
PAINT MONO (10850 4275);
DISPLAY INVISIBLE (10850 4275);
FORCEPROP 1 LAST BODY_TYPE PLUMBING
J 0
(10805 4232);
DISPLAY 0.340426 (10805 4232);
PAINT GREEN (10805 4232);
DISPLAY INVISIBLE (10805 4232);
FORCEPROP 1 LAST PATH I9
J 0
(10925 4275);
DISPLAY 0.872340 (10925 4275);
PAINT AQUA (10925 4275);
DISPLAY INVISIBLE (10925 4275);
FORCEPROP 1 LAST HDL_POWER GND
J 0
(10850 4425);
DISPLAY 0.872340 (10850 4425);
PAINT GREEN (10850 4425);
DISPLAY INVISIBLE (10850 4425);
FORCEPROP 1 LAST VOLTAGE 0
J 0
(10850 4275);
PAINT SKYBLUE (10850 4275);
DISPLAY INVISIBLE (10850 4275);
FORCEADD CAD_NOTE..1
(4350 3875);
FORCEPROP 0 LAST L5 RMII_BMC_OCP_RXD1_R
J 0
(4200 3450);
DISPLAY 1.021277 (4200 3450);
PAINT ORANGE (4200 3450);
FORCEPROP 0 LAST L6 RMII_BMC_OCP_RXER_R
J 0
(4200 3375);
DISPLAY 1.021277 (4200 3375);
PAINT ORANGE (4200 3375);
FORCEPROP 0 LAST L4 RMII_BMC_OCP_RXD0_R
J 0
(4200 3525);
DISPLAY 1.021277 (4200 3525);
PAINT ORANGE (4200 3525);
FORCEPROP 0 LAST L3 RMII_BMC_OCP_CRSDV_R
J 0
(4200 3600);
DISPLAY 1.021277 (4200 3600);
PAINT ORANGE (4200 3600);
FORCEPROP 0 LAST L2 NETS WITHIN 2 INCHES OF THE OCP CONNECTOR:
J 0
(4200 3675);
DISPLAY 1.021277 (4200 3675);
PAINT ORANGE (4200 3675);
FORCEPROP 0 LAST L1 PLACE SERIES RESISTORS ON THE FOLLOWING
J 0
(4200 3750);
DISPLAY 1.021277 (4200 3750);
PAINT ORANGE (4200 3750);
FORCEPROP 2 LAST CDS_LIB mstr_symbols
J 0
(4350 3875);
PAINT ORANGE (4350 3875);
DISPLAY INVISIBLE (4350 3875);
FORCEPROP 1 LAST COMMENT_BODY TRUE
J 0
(4375 3975);
DISPLAY 0.978723 (4375 3975);
PAINT ORANGE (4375 3975);
DISPLAY INVISIBLE (4375 3975);
FORCEADD DESIGN_NOTE..1
(9300 4800);
FORCEPROP 0 LAST L1 13MM HT CONNECTOR IN SCHEMATIC
J 0
(9100 4675);
DISPLAY 1.021277 (9100 4675);
PAINT ORANGE (9100 4675);
FORCEPROP 0 LAST L2 12MM HT CONNECTOR IN BOM
J 0
(9100 4600);
DISPLAY 1.021277 (9100 4600);
PAINT ORANGE (9100 4600);
FORCEPROP 2 LAST CDS_LIB mstr_symbols
J 0
(9300 4800);
PAINT ORANGE (9300 4800);
DISPLAY INVISIBLE (9300 4800);
FORCEPROP 1 LAST COMMENT_BODY TRUE
J 0
(9325 4900);
DISPLAY 0.978723 (9325 4900);
PAINT ORANGE (9325 4900);
DISPLAY INVISIBLE (9325 4900);
FORCEADD INTEL_CORP_BPAGE..1
(12075 200);
FORCEPROP 1 LAST CDS_CON_LAST_MODIFIED Tue Dec 01 11:52:16 2015
J 0
(10650 525);
PAINT ORANGE (10650 525);
DISPLAY INVISIBLE (10650 525);
FORCEPROP 1 LAST CUSTOM_TXT_CDS <CURRENT_DESIGN_SHEET> OF <TOTAL_DESIGN_SHEETS>
J 0
(11575 225);
PAINT GREEN (11575 225);
FORCEPROP 1 LAST CUSTOM_TXT_CDS <CON_LAST_MODIFIED>
J 0
(10150 550);
PAINT GREEN (10150 550);
FORCEPROP 2 LAST CUSTOM_TXT_CDS <XR_PAGE_TITLE>
J 0
(4185 5450);
DISPLAY 0.638298 (4185 5450);
PAINT PINK (4185 5450);
DISPLAY INVISIBLE (4185 5450);
FORCEPROP 1 LAST SCH_TITLE OCP MODULE CONN A
J 0
(4125 250);
DISPLAY 1.212766 (4125 250);
PAINT ORANGE (4125 250);
FORCEPROP 1 LAST SCH_ADDRESS1 2200 Mission College Blvd.
J 0
(8100 325);
DISPLAY 0.617021 (8100 325);
PAINT GREEN (8100 325);
FORCEPROP 1 LAST SCH_ADDRESS2 P.O. BOX 58119
J 0
(8100 275);
DISPLAY 0.617021 (8100 275);
PAINT GREEN (8100 275);
FORCEPROP 1 LAST SCH_ADDRESS3 Santa Clara, CA 95052-8119
J 0
(8100 225);
DISPLAY 0.617021 (8100 225);
PAINT GREEN (8100 225);
FORCEPROP 1 LAST SCH_NUMBER H4694802
J 0
(10775 350);
DISPLAY 1.212766 (10775 350);
PAINT YELLOW (10775 350);
FORCEPROP 1 LAST SCH_DEPT BESD
J 1
(7625 300);
DISPLAY 1.212766 (7625 300);
PAINT YELLOW (7625 300);
FORCEPROP 1 LAST SCH_REV 2.420
J 0
(11825 350);
DISPLAY 0.978723 (11825 350);
PAINT YELLOW (11825 350);
FORCEPROP 2 LAST PAGE_BORDER TRUE
J 0
(4185 5450);
DISPLAY 0.638298 (4185 5450);
PAINT PINK (4185 5450);
DISPLAY INVISIBLE (4185 5450);
FORCEPROP 2 LAST CDS_LIB mstr_symbols
J 0
(12075 200);
PAINT MONO (12075 200);
DISPLAY INVISIBLE (12075 200);
FORCEPROP 1 LAST COMMENT_BODY TRUE
J 0
(12087 212);
DISPLAY 0.468085 (12087 212);
PAINT GREEN (12087 212);
DISPLAY INVISIBLE (12087 212);
FORCEPROP 2 LAST CDS_XR_PAGE_TITLE CR-186 : @BASEBOARD_FAB2_LIB.BASEBOARD_FAB2(SCH_1):PAGE186
J 0
(4185 5450);
DISPLAY 0.638298 (4185 5450);
PAINT PINK (4185 5450);
DISPLAY INVISIBLE (4185 5450);
WIRE 17 -1 (6375 2625)(6375 2425);
WIRE 17 -1 (6375 2625)(5200 2625);
FORCEPROP 2 LAST SIG_NAME P3E_CPU0_PE3_OCP_RXP<15:8>
J 0
(5200 2636);
DISPLAY 0.617021 (5200 2636);
PAINT ORANGE (5200 2636);
WIRE 17 -1 (6200 2575)(6200 2375);
WIRE 17 -1 (6200 2575)(5200 2575);
FORCEPROP 2 LAST SIG_NAME P3E_CPU0_PE3_OCP_RXN<15:8>
J 0
(5197 2585);
DISPLAY 0.617021 (5197 2585);
PAINT ORANGE (5197 2585);
WIRE 17 -1 (6375 2425)(6375 2225);
WIRE 17 -1 (6375 2225)(6375 2025);
WIRE 17 -1 (6375 1825)(6375 2025);
WIRE 17 -1 (6200 2375)(6200 2175);
WIRE 17 -1 (6200 2175)(6200 1975);
WIRE 17 -1 (6200 1975)(6200 1775);
WIRE 17 -1 (6375 1825)(6375 1625);
WIRE 17 -1 (6200 1775)(6200 1575);
WIRE 17 -1 (6375 1625)(6375 1425);
WIRE 17 -1 (6375 1425)(6375 1225);
WIRE 17 -1 (6200 1575)(6200 1375);
WIRE 17 -1 (6200 1375)(6200 1175);
WIRE 17 -1 (6200 1175)(6200 975);
WIRE 17 -1 (6375 1225)(6375 1025);
WIRE 17 -1 (10100 2575)(10100 2525);
WIRE 17 -1 (10100 2575)(10975 2575);
FORCEPROP 0 LAST SIG_NAME P3E_OCP_CPU0_PE3_C_TXP<15:8>
J 0
(10300 2585);
DISPLAY 0.617021 (10300 2585);
PAINT ORANGE (10300 2585);
WIRE 17 -1 (10300 2500)(10300 2475);
WIRE 17 -1 (10300 2500)(10975 2500);
FORCEPROP 0 LAST SIG_NAME P3E_OCP_CPU0_PE3_C_TXN<15:8>
J 0
(10300 2510);
DISPLAY 0.617021 (10300 2510);
PAINT ORANGE (10300 2510);
WIRE 17 -1 (10100 2325)(10100 2525);
WIRE 17 -1 (10100 2325)(10100 2125);
WIRE 17 -1 (10300 2475)(10300 2275);
WIRE 17 -1 (10300 2075)(10300 2275);
WIRE 17 -1 (10300 1875)(10300 2075);
WIRE 17 -1 (10100 2125)(10100 1925);
WIRE 17 -1 (10100 1725)(10100 1925);
WIRE 17 -1 (10300 1675)(10300 1875);
WIRE 17 -1 (10300 1475)(10300 1675);
WIRE 17 -1 (10100 1525)(10100 1725);
WIRE 17 -1 (10100 1325)(10100 1525);
WIRE 17 -1 (10100 1325)(10100 1125);
WIRE 17 -1 (10300 1275)(10300 1475);
WIRE 17 -1 (10300 1075)(10300 1275);
WIRE 16 -1 (10450 3875)(10450 3700);
WIRE 16 -1 (10450 3700)(10850 3700);
WIRE 16 -1 (10850 3700)(11225 3700);
WIRE 16 -1 (10850 3700)(10850 3850);
WIRE 16 -1 (11225 3700)(11650 3700);
WIRE 16 -1 (11225 3700)(11225 3850);
WIRE 16 -1 (11650 3850)(11650 3700);
WIRE 16 -1 (11650 3700)(11650 3600);
WIRE 16 -1 (7850 3650)(7525 3650);
WIRE 16 -1 (7525 3650)(7525 3600);
WIRE 16 -1 (7850 3600)(7525 3600);
WIRE 16 -1 (7525 3600)(7525 3500);
WIRE 16 -1 (7850 3500)(7525 3500);
WIRE 16 -1 (7525 3500)(7525 3450);
WIRE 16 -1 (7850 3450)(7525 3450);
WIRE 16 -1 (7525 2900)(7525 3450);
WIRE 16 -1 (7850 2900)(7525 2900);
WIRE 16 -1 (7525 2850)(7525 2900);
WIRE 16 -1 (7850 2850)(7525 2850);
WIRE 16 -1 (7525 2700)(7525 2850);
WIRE 16 -1 (7850 2700)(7525 2700);
WIRE 16 -1 (7525 2650)(7525 2700);
WIRE 16 -1 (7850 2650)(7525 2650);
WIRE 16 -1 (7525 2500)(7525 2650);
WIRE 16 -1 (7850 2500)(7525 2500);
WIRE 16 -1 (7525 2450)(7525 2500);
WIRE 16 -1 (7850 2450)(7525 2450);
WIRE 16 -1 (7525 2300)(7525 2450);
WIRE 16 -1 (7850 2300)(7525 2300);
WIRE 16 -1 (7525 2250)(7525 2300);
WIRE 16 -1 (7850 2250)(7525 2250);
WIRE 16 -1 (7525 2250)(7525 2100);
WIRE 16 -1 (7850 2100)(7525 2100);
WIRE 16 -1 (7525 2100)(7525 2050);
WIRE 16 -1 (7850 2050)(7525 2050);
WIRE 16 -1 (7525 2050)(7525 1900);
WIRE 16 -1 (7850 1900)(7525 1900);
WIRE 16 -1 (7525 1850)(7525 1900);
WIRE 16 -1 (7850 1850)(7525 1850);
WIRE 16 -1 (7525 1700)(7525 1850);
WIRE 16 -1 (7850 1700)(7525 1700);
WIRE 16 -1 (7525 1650)(7525 1700);
WIRE 16 -1 (7850 1650)(7525 1650);
WIRE 16 -1 (7525 1500)(7525 1650);
WIRE 16 -1 (7850 1500)(7525 1500);
WIRE 16 -1 (7525 1450)(7525 1500);
WIRE 16 -1 (7850 1450)(7525 1450);
WIRE 16 -1 (7525 1300)(7525 1450);
WIRE 16 -1 (7850 1300)(7525 1300);
WIRE 16 -1 (7525 1250)(7525 1300);
WIRE 16 -1 (7850 1250)(7525 1250);
WIRE 16 -1 (7525 1100)(7525 1250);
WIRE 16 -1 (7850 1100)(7525 1100);
WIRE 16 -1 (7525 1050)(7525 1100);
WIRE 16 -1 (7850 1050)(7525 1050);
WIRE 16 -1 (7525 900)(7525 1050);
WIRE 16 -1 (7850 900)(7525 900);
WIRE 16 -1 (7525 750)(7525 900);
WIRE 16 -1 (8650 3700)(8975 3700);
WIRE 16 -1 (8975 3700)(8975 3650);
WIRE 16 -1 (8650 3650)(8975 3650);
WIRE 16 -1 (8975 3650)(8975 3550);
WIRE 16 -1 (8650 3550)(8975 3550);
WIRE 16 -1 (8975 3550)(8975 3500);
WIRE 16 -1 (8650 3500)(8975 3500);
WIRE 16 -1 (8975 3250)(8975 3500);
WIRE 16 -1 (8650 3250)(8975 3250);
WIRE 16 -1 (8975 2950)(8975 3250);
WIRE 16 -1 (8650 2950)(8975 2950);
WIRE 16 -1 (8975 2800)(8975 2950);
WIRE 16 -1 (8650 2800)(8975 2800);
WIRE 16 -1 (8975 2750)(8975 2800);
WIRE 16 -1 (8650 2750)(8975 2750);
WIRE 16 -1 (8975 2600)(8975 2750);
WIRE 16 -1 (8650 2600)(8975 2600);
WIRE 16 -1 (8975 2550)(8975 2600);
WIRE 16 -1 (8650 2550)(8975 2550);
WIRE 16 -1 (8975 2400)(8975 2550);
WIRE 16 -1 (8650 2400)(8975 2400);
WIRE 16 -1 (8975 2350)(8975 2400);
WIRE 16 -1 (8650 2350)(8975 2350);
WIRE 16 -1 (8975 2200)(8975 2350);
WIRE 16 -1 (8650 2200)(8975 2200);
WIRE 16 -1 (8975 2150)(8975 2200);
WIRE 16 -1 (8650 2150)(8975 2150);
WIRE 16 -1 (8975 2000)(8975 2150);
WIRE 16 -1 (8650 2000)(8975 2000);
WIRE 16 -1 (8975 1950)(8975 2000);
WIRE 16 -1 (8650 1950)(8975 1950);
WIRE 16 -1 (8975 1800)(8975 1950);
WIRE 16 -1 (8650 1800)(8975 1800);
WIRE 16 -1 (8975 1750)(8975 1800);
WIRE 16 -1 (8650 1750)(8975 1750);
WIRE 16 -1 (8975 1600)(8975 1750);
WIRE 16 -1 (8650 1600)(8975 1600);
WIRE 16 -1 (8975 1550)(8975 1600);
WIRE 16 -1 (8650 1550)(8975 1550);
WIRE 16 -1 (8975 1400)(8975 1550);
WIRE 16 -1 (8650 1400)(8975 1400);
WIRE 16 -1 (8975 1350)(8975 1400);
WIRE 16 -1 (8650 1350)(8975 1350);
WIRE 16 -1 (8975 1200)(8975 1350);
WIRE 16 -1 (8650 1200)(8975 1200);
WIRE 16 -1 (8975 1150)(8975 1200);
WIRE 16 -1 (8650 1150)(8975 1150);
WIRE 16 -1 (8975 1000)(8975 1150);
WIRE 16 -1 (8650 1000)(8975 1000);
WIRE 16 -1 (8975 950)(8975 1000);
WIRE 16 -1 (8650 950)(8975 950);
WIRE 16 -1 (8975 775)(8975 950);
WIRE 16 -1 (7850 3250)(7000 3250);
WIRE 16 -1 (7000 3250)(7000 3300);
WIRE 16 -1 (7850 3300)(7000 3300);
WIRE 16 -1 (7000 3300)(7000 3350);
WIRE 16 -1 (7850 3350)(7000 3350);
WIRE 16 -1 (7000 3350)(7000 3400);
WIRE 16 -1 (7050 3400)(7000 3400);
WIRE 16 -1 (7850 3400)(7050 3400);
WIRE 16 -1 (7050 3400)(7050 4000);
WIRE 16 -1 (6400 3850)(6325 3850);
WIRE 16 -1 (6325 3675)(6325 3850);
WIRE 16 -1 (8850 3350)(8850 3300);
WIRE 16 -1 (8850 3400)(8850 3350);
WIRE 16 -1 (8850 3350)(8650 3350);
WIRE 16 -1 (8850 3300)(8650 3300);
WIRE 16 -1 (8850 3450)(8850 3400);
WIRE 16 -1 (8850 3400)(8650 3400);
WIRE 16 -1 (8850 4000)(8850 3450);
WIRE 16 -1 (8850 3450)(8650 3450);
WIRE 16 -1 (10850 4875)(10850 4775);
WIRE 16 -1 (10450 4875)(10850 4875);
WIRE 16 -1 (10450 4800)(10450 4875);
WIRE 16 -1 (10450 4875)(10450 4900);
WIRE 16 -1 (11650 4400)(11250 4400);
WIRE 16 -1 (11650 4575)(11650 4400);
WIRE 16 -1 (11650 4325)(11650 4400);
WIRE 16 -1 (11250 4400)(11250 4600);
WIRE 16 -1 (7850 3550)(7375 3550);
WIRE 16 -1 (7375 3975)(7375 3550);
WIRE 16 -1 (8725 4150)(8725 3600);
WIRE 16 -1 (8725 3600)(8650 3600);
WIRE 16 -1 (7650 3700)(7850 3700);
WIRE 16 -1 (7650 3750)(7650 3700);
WIRE 16 -1 (7650 3750)(7850 3750);
WIRE 16 -1 (7650 3800)(7650 3750);
WIRE 16 -1 (7850 3800)(7650 3800);
WIRE 16 -1 (7650 3800)(7650 4000);
WIRE 16 -1 (8650 3750)(8975 3750);
WIRE 16 -1 (8975 3800)(8975 3750);
WIRE 16 -1 (8650 3800)(8975 3800);
WIRE 16 -1 (8975 3850)(8975 3800);
WIRE 16 -1 (8650 3850)(8975 3850);
WIRE 16 -1 (9200 3850)(8975 3850);
WIRE 16 -1 (9200 3850)(9200 4175);
WIRE 16 -1 (11650 4150)(11225 4150);
WIRE 16 -1 (11650 4150)(11650 4050);
WIRE 16 -1 (11225 4150)(10850 4150);
WIRE 16 -1 (11225 4150)(11225 4050);
WIRE 16 -1 (10450 4150)(10850 4150);
WIRE 16 -1 (10850 4150)(10850 4050);
WIRE 16 -1 (10450 4175)(10450 4150);
WIRE 16 -1 (10450 4150)(10450 4075);
WIRE 16 -1 (11650 4875)(11650 4775);
WIRE 16 -1 (11250 4875)(11650 4875);
WIRE 16 -1 (11250 4800)(11250 4875);
WIRE 16 -1 (11250 4875)(11250 4900);
WIRE 16 -1 (10050 3700)(9650 3700);
WIRE 16 -1 (10050 3850)(10050 3700);
WIRE 16 -1 (10050 3600)(10050 3700);
WIRE 16 -1 (9650 3700)(9650 3850);
WIRE 16 -1 (9650 4150)(10050 4150);
WIRE 16 -1 (9650 4050)(9650 4150);
WIRE 16 -1 (9650 4150)(9650 4175);
WIRE 16 -1 (10050 4150)(10050 4050);
WIRE 16 -1 (10850 4400)(10450 4400);
WIRE 16 -1 (10850 4575)(10850 4400);
WIRE 16 -1 (10850 4325)(10850 4400);
WIRE 16 -1 (10450 4400)(10450 4600);
WIRE 16 -1 (8975 5000)(8975 4825);
WIRE 16 -1 (8975 5000)(8250 5000);
WIRE 16 -1 (8975 4725)(8975 4825);
WIRE 16 -1 (4200 4825)(8975 4825);
WIRE 16 -1 (4200 5000)(4200 4825);
WIRE 16 -1 (4200 4725)(4200 4825);
WIRE 16 -1 (8975 4625)(8975 4725);
WIRE 16 -1 (4200 4725)(8975 4725);
WIRE 16 -1 (8250 5000)(8250 4525);
WIRE 16 -1 (8250 5000)(7600 5000);
WIRE 16 -1 (7600 5000)(7600 4525);
WIRE 16 -1 (7600 5000)(6900 5000);
WIRE 16 -1 (8975 4525)(8250 4525);
WIRE 16 -1 (8250 4525)(7600 4525);
WIRE 16 -1 (4200 4725)(4200 4625);
WIRE 16 -1 (8975 4625)(8975 4525);
WIRE 16 -1 (4200 4625)(8975 4625);
WIRE 16 -1 (4200 5000)(4500 5000);
WIRE 16 -1 (4500 5000)(5350 5000);
WIRE 16 -1 (4500 5000)(4500 4525);
WIRE 16 -1 (4200 4625)(4200 4525);
WIRE 16 -1 (7600 4525)(6900 4525);
WIRE 16 -1 (6900 5000)(6900 4525);
WIRE 16 -1 (6900 5000)(6225 5000);
WIRE 16 -1 (6225 5000)(5350 5000);
WIRE 16 -1 (6225 5000)(6225 4525);
WIRE 16 -1 (6900 4525)(6225 4525);
WIRE 16 -1 (4200 4525)(4500 4525);
WIRE 16 -1 (4500 4525)(5350 4525);
WIRE 16 -1 (5350 5000)(5350 4525);
WIRE 16 -1 (6225 4525)(5350 4525);
WIRE 16 -1 (7850 3850)(6600 3850);
FORCEPROP 0 LAST SIG_NAME FM_MEZZA_PRSNT1_N
J 1
(6938 3860);
DISPLAY 0.617021 (6938 3860);
PAINT ORANGE (6938 3860);
FORCEPROP 2 LASTPROP $XRERR UNIQUE?
J 0
(6698 3860);
DISPLAY 0.638298 (6698 3860);
PAINT MONO (6698 3860);
DISPLAY INVISIBLE (6698 3860);
WIRE 16 -1 (5200 2800)(6275 2800);
FORCEPROP 2 LAST SIG_NAME RMII_BMC_OCP_RXD0
J 0
(5200 2810);
DISPLAY 0.617021 (5200 2810);
PAINT ORANGE (5200 2810);
WIRE 16 -1 (5200 3200)(6275 3200);
FORCEPROP 2 LAST SIG_NAME RMII_BMC_OCP_CRSDV
J 0
(5200 3210);
DISPLAY 0.617021 (5200 3210);
PAINT ORANGE (5200 3210);
WIRE 16 -1 (5200 3050)(5900 3050);
FORCEPROP 0 LAST SIG_NAME RST_PCIE_CPU_DEV0_N
J 0
(5200 3060);
DISPLAY 0.617021 (5200 3060);
PAINT ORANGE (5200 3060);
WIRE 16 -1 (8650 900)(9775 900);
FORCEPROP 0 LAST SIG_NAME FM_OCP_MEZZA_PRES_N
J 1
(9463 910);
DISPLAY 0.617021 (9463 910);
PAINT ORANGE (9463 910);
WIRE 16 -1 (8650 1050)(10200 1050);
WIRE 16 -1 (8650 1100)(10000 1100);
WIRE 16 -1 (8650 1250)(10200 1250);
WIRE 16 -1 (8650 1300)(10000 1300);
WIRE 16 -1 (8650 1450)(10200 1450);
WIRE 16 -1 (8650 1500)(10000 1500);
WIRE 16 -1 (8650 1700)(10000 1700);
WIRE 16 -1 (8650 1650)(10200 1650);
WIRE 16 -1 (8650 1850)(10200 1850);
WIRE 16 -1 (8650 1900)(10000 1900);
WIRE 16 -1 (8650 2050)(10200 2050);
WIRE 16 -1 (8650 2100)(10000 2100);
WIRE 16 -1 (8650 2250)(10200 2250);
WIRE 16 -1 (8650 2300)(10000 2300);
WIRE 16 -1 (8650 2450)(10200 2450);
WIRE 16 -1 (8650 2500)(10000 2500);
WIRE 16 -1 (8650 2650)(9700 2650);
FORCEPROP 0 LAST SIG_NAME CLK_100M_MEZZ1_DN
J 1
(9213 2660);
DISPLAY 0.617021 (9213 2660);
PAINT ORANGE (9213 2660);
WIRE 16 -1 (8650 2700)(9700 2700);
FORCEPROP 0 LAST SIG_NAME CLK_100M_MEZZ1_DP
J 1
(9213 2710);
DISPLAY 0.617021 (9213 2710);
PAINT ORANGE (9213 2710);
WIRE 16 -1 (8650 2850)(9700 2850);
FORCEPROP 0 LAST SIG_NAME RMII_BMC_OCP_TXD1
J 0
(9125 2860);
DISPLAY 0.617021 (9125 2860);
PAINT ORANGE (9125 2860);
WIRE 16 -1 (8650 2900)(9700 2900);
FORCEPROP 0 LAST SIG_NAME RMII_BMC_OCP_TXD0
J 0
(9125 2910);
DISPLAY 0.617021 (9125 2910);
PAINT ORANGE (9125 2910);
WIRE 16 -1 (8650 3000)(10150 3000);
FORCEPROP 0 LAST SIG_NAME RMII_BMC_OCP_RXER_R
J 0
(9125 3010);
DISPLAY 0.617021 (9125 3010);
PAINT ORANGE (9125 3010);
FORCEPROP 2 LASTPROP $XRERR UNIQUE?
J 0
(8885 3010);
DISPLAY 0.638298 (8885 3010);
PAINT MONO (8885 3010);
DISPLAY INVISIBLE (8885 3010);
WIRE 16 -1 (8650 3100)(9700 3100);
FORCEPROP 0 LAST SIG_NAME SMB_OCP_FRU_STBY_LVC3_SDA
J 0
(9125 3110);
DISPLAY 0.617021 (9125 3110);
PAINT ORANGE (9125 3110);
WIRE 16 -1 (8650 3050)(9700 3050);
FORCEPROP 0 LAST SIG_NAME FM_PE_OCP_WAKE_N
J 0
(9125 3060);
DISPLAY 0.617021 (9125 3060);
PAINT ORANGE (9125 3060);
WIRE 16 -1 (8650 3150)(9700 3150);
FORCEPROP 0 LAST SIG_NAME SMB_OCP_FRU_STBY_LVC3_SCL
J 0
(9125 3160);
DISPLAY 0.617021 (9125 3160);
PAINT ORANGE (9125 3160);
WIRE 16 -1 (8650 3200)(9700 3200);
FORCEPROP 0 LAST SIG_NAME IRQ_MEZZ_LAN_ALERT_N
J 0
(9125 3210);
DISPLAY 0.617021 (9125 3210);
PAINT ORANGE (9125 3210);
WIRE 16 -1 (7850 950)(6300 950);
WIRE 16 -1 (7850 1000)(6475 1000);
WIRE 16 -1 (7850 1150)(6300 1150);
WIRE 16 -1 (7850 1200)(6475 1200);
WIRE 16 -1 (7850 1350)(6300 1350);
WIRE 16 -1 (7850 1400)(6475 1400);
WIRE 16 -1 (7850 1550)(6300 1550);
WIRE 16 -1 (7850 1600)(6475 1600);
WIRE 16 -1 (7850 1750)(6300 1750);
WIRE 16 -1 (7850 1800)(6475 1800);
WIRE 16 -1 (7850 1950)(6300 1950);
WIRE 16 -1 (7850 2000)(6475 2000);
WIRE 16 -1 (7850 2150)(6300 2150);
WIRE 16 -1 (7850 2200)(6475 2200);
WIRE 16 -1 (7850 2600)(6875 2600);
FORCEPROP 0 LAST SIG_NAME CLK_100M_MEZZ2_DP
J 0
(6875 2610);
DISPLAY 0.617021 (6875 2610);
PAINT ORANGE (6875 2610);
WIRE 16 -1 (7850 2550)(6875 2550);
FORCEPROP 0 LAST SIG_NAME CLK_100M_MEZZ2_DN
J 0
(6875 2560);
DISPLAY 0.617021 (6875 2560);
PAINT ORANGE (6875 2560);
WIRE 16 -1 (7850 2750)(6800 2750);
FORCEPROP 0 LAST SIG_NAME RMII_BMC_OCP_RXD1_R
J 0
(6875 2760);
DISPLAY 0.617021 (6875 2760);
PAINT ORANGE (6875 2760);
FORCEPROP 2 LASTPROP $XRERR UNIQUE?
J 0
(6635 2760);
DISPLAY 0.638298 (6635 2760);
PAINT MONO (6635 2760);
DISPLAY INVISIBLE (6635 2760);
WIRE 16 -1 (7850 2950)(6875 2950);
FORCEPROP 0 LAST SIG_NAME SMB_OCP_LAN_STBY_LVC3_SDA
J 0
(6875 2960);
DISPLAY 0.617021 (6875 2960);
PAINT ORANGE (6875 2960);
WIRE 16 -1 (7850 3000)(6875 3000);
FORCEPROP 0 LAST SIG_NAME SMB_OCP_LAN_STBY_LVC3_SCL
J 0
(6875 3010);
DISPLAY 0.617021 (6875 3010);
PAINT ORANGE (6875 3010);
WIRE 16 -1 (7850 3100)(6875 3100);
FORCEPROP 0 LAST SIG_NAME RMII_BMC_OCP_TXEN
J 0
(6875 3110);
DISPLAY 0.617021 (6875 3110);
PAINT ORANGE (6875 3110);
WIRE 16 -1 (7850 3050)(6100 3050);
FORCEPROP 0 LAST SIG_NAME RST_PCIE_CPU_DEV0_R_N
J 0
(6850 3060);
DISPLAY 0.617021 (6850 3060);
PAINT ORANGE (6850 3060);
FORCEPROP 2 LASTPROP $XRERR UNIQUE?
J 0
(6610 3060);
DISPLAY 0.638298 (6610 3060);
PAINT MONO (6610 3060);
DISPLAY INVISIBLE (6610 3060);
WIRE 16 -1 (7850 3150)(6875 3150);
FORCEPROP 0 LAST SIG_NAME CLK_50M_CKMNG_OCP
J 0
(6875 3160);
DISPLAY 0.617021 (6875 3160);
PAINT ORANGE (6875 3160);
WIRE 16 -1 (7850 3200)(6475 3200);
FORCEPROP 0 LAST SIG_NAME RMII_BMC_OCP_CRSDV_R
J 0
(6875 3210);
DISPLAY 0.617021 (6875 3210);
PAINT ORANGE (6875 3210);
FORCEPROP 2 LASTPROP $XRERR UNIQUE?
J 0
(6635 3210);
DISPLAY 0.638298 (6635 3210);
PAINT MONO (6635 3210);
DISPLAY INVISIBLE (6635 3210);
WIRE 16 -1 (10350 3000)(11050 3000);
FORCEPROP 2 LAST SIG_NAME RMII_BMC_OCP_RXER
J 0
(10465 3010);
DISPLAY 0.617021 (10465 3010);
PAINT ORANGE (10465 3010);
WIRE 16 -1 (7850 2350)(6300 2350);
WIRE 16 -1 (7850 2400)(6475 2400);
WIRE 16 -1 (5200 2750)(6600 2750);
FORCEPROP 2 LAST SIG_NAME RMII_BMC_OCP_RXD1
J 0
(5200 2760);
DISPLAY 0.617021 (5200 2760);
PAINT ORANGE (5200 2760);
WIRE 16 -1 (6475 2800)(7850 2800);
FORCEPROP 0 LAST SIG_NAME RMII_BMC_OCP_RXD0_R
J 0
(6875 2810);
DISPLAY 0.617021 (6875 2810);
PAINT ORANGE (6875 2810);
FORCEPROP 2 LASTPROP $XRERR UNIQUE?
J 0
(6635 2810);
DISPLAY 0.638298 (6635 2810);
PAINT MONO (6635 2810);
DISPLAY INVISIBLE (6635 2810);
DOT 1 (7000 3350);
DOT 1 (6900 4525);
DOT 1 (6225 4525);
DOT 1 (8975 1550);
DOT 1 (7525 1900);
DOT 1 (7525 3450);
DOT 1 (8975 2750);
DOT 1 (8850 3350);
DOT 1 (8975 3500);
DOT 1 (8850 3450);
DOT 1 (8975 2600);
DOT 1 (8975 3250);
DOT 1 (8975 1000);
DOT 1 (8975 950);
DOT 1 (8975 1150);
DOT 1 (8975 1200);
DOT 1 (8975 1350);
DOT 1 (8975 1400);
DOT 1 (8975 1750);
DOT 1 (8975 1800);
DOT 1 (8975 1950);
DOT 1 (8975 2000);
DOT 1 (8975 2200);
DOT 1 (8975 2150);
DOT 1 (8975 2350);
DOT 1 (8975 2400);
DOT 1 (8975 2550);
DOT 1 (8975 2800);
DOT 1 (8975 2950);
DOT 1 (8850 3400);
DOT 1 (8975 3550);
DOT 1 (8975 3850);
DOT 1 (8975 3800);
DOT 1 (8975 3650);
DOT 1 (7525 900);
DOT 1 (7525 1100);
DOT 1 (7525 1050);
DOT 1 (7525 1250);
DOT 1 (7525 1300);
DOT 1 (7525 1450);
DOT 1 (7525 1500);
DOT 1 (7525 1650);
DOT 1 (7525 1700);
DOT 1 (7525 1850);
DOT 1 (7525 2050);
DOT 1 (7525 2100);
DOT 1 (7525 2250);
DOT 1 (7525 2300);
DOT 1 (7525 2450);
DOT 1 (7525 2500);
DOT 1 (7525 2650);
DOT 1 (7525 2700);
DOT 1 (7000 3300);
DOT 1 (7525 2900);
DOT 1 (7525 2850);
DOT 1 (7525 3500);
DOT 1 (7650 3750);
DOT 1 (7650 3800);
DOT 1 (7525 3600);
DOT 1 (7050 3400);
DOT 1 (8975 1600);
DOT 1 (4500 4525);
DOT 1 (4200 4725);
DOT 1 (4200 4625);
DOT 1 (4200 4825);
DOT 1 (4500 5000);
DOT 1 (5350 5000);
DOT 1 (5350 4525);
DOT 1 (6225 5000);
DOT 1 (6900 5000);
DOT 1 (7600 5000);
DOT 1 (8250 5000);
DOT 1 (8975 4625);
DOT 1 (8975 4725);
DOT 1 (8975 4825);
DOT 1 (10850 4400);
DOT 1 (10450 4875);
DOT 1 (10850 4150);
DOT 1 (11225 4150);
DOT 1 (11650 3700);
DOT 1 (11225 3700);
DOT 1 (11250 4875);
DOT 1 (11650 4400);
DOT 1 (9650 4150);
DOT 1 (10050 3700);
DOT 1 (8250 4525);
DOT 1 (7600 4525);
DOT 1 (10450 4150);
DOT 1 (10850 3700);
FORCENOTE
61083-121402LF
(4550 4750) 0;
DISPLAY LEFT (4550 4750);
DISPLAY 1.021277 (4550 4750);
PAINT PURPLE (4550 4750);
FORCENOTE
(12 MM STACK)
(8275 4850) 0;
DISPLAY LEFT (8275 4850);
DISPLAY 1.021277 (8275 4850);
PAINT PURPLE (8275 4850);
FORCENOTE
10135583-642402LF
(7625 4550) 0;
DISPLAY LEFT (7625 4550);
DISPLAY 1.021277 (7625 4550);
PAINT PURPLE (7625 4550);
FORCENOTE
61082-082402LF
(7625 4650) 0;
DISPLAY LEFT (7625 4650);
DISPLAY 1.021277 (7625 4650);
PAINT PURPLE (7625 4650);
FORCENOTE
(5/8MM STACK)
(6950 4850) 0;
DISPLAY LEFT (6950 4850);
DISPLAY 1.021277 (6950 4850);
PAINT PURPLE (6950 4850);
FORCENOTE
FCI RECPT IPN ON CC
(6925 4925) 0;
DISPLAY LEFT (6925 4925);
DISPLAY 1.021277 (6925 4925);
PAINT PURPLE (6925 4925);
FORCENOTE
A28699-010
(6950 4750) 0;
DISPLAY LEFT (6950 4750);
DISPLAY 1.021277 (6950 4750);
PAINT PURPLE (6950 4750);
FORCENOTE
(5/8MM STACK)
(6275 4850) 0;
DISPLAY LEFT (6275 4850);
DISPLAY 1.021277 (6275 4850);
PAINT PURPLE (6275 4850);
FORCENOTE
61082-081402LF
(6275 4650) 0;
DISPLAY LEFT (6275 4650);
DISPLAY 1.021277 (6275 4650);
PAINT PURPLE (6275 4650);
FORCENOTE
10135583-641402LF
(6275 4550) 0;
DISPLAY LEFT (6275 4550);
DISPLAY 1.021277 (6275 4550);
PAINT PURPLE (6275 4550);
FORCENOTE
FCI RECPT # ON CC
(6275 4925) 0;
DISPLAY LEFT (6275 4925);
DISPLAY 1.021277 (6275 4925);
PAINT PURPLE (6275 4925);
FORCENOTE
FCI PLUG # ON OCP MEZZ
(5400 4925) 0;
DISPLAY LEFT (5400 4925);
DISPLAY 1.021277 (5400 4925);
PAINT PURPLE (5400 4925);
FORCENOTE
(8/12 MM STACK)
(5400 4850) 0;
DISPLAY LEFT (5400 4850);
DISPLAY 1.021277 (5400 4850);
PAINT PURPLE (5400 4850);
FORCENOTE
61083-124402LF
(5400 4750) 0;
DISPLAY LEFT (5400 4750);
DISPLAY 1.021277 (5400 4750);
PAINT PURPLE (5400 4750);
FORCENOTE
61083-084402LF
(5400 4650) 0;
DISPLAY LEFT (5400 4650);
DISPLAY 1.021277 (5400 4650);
PAINT PURPLE (5400 4650);
FORCENOTE
61082-081402LF
(4550 4650) 0;
DISPLAY LEFT (4550 4650);
DISPLAY 1.021277 (4550 4650);
PAINT PURPLE (4550 4650);
FORCENOTE
10135584-641402LF
(4550 4550) 0;
DISPLAY LEFT (4550 4550);
DISPLAY 1.021277 (4550 4550);
PAINT PURPLE (4550 4550);
FORCENOTE
A (120P)
(4225 4750) 0;
DISPLAY LEFT (4225 4750);
DISPLAY 1.021277 (4225 4750);
PAINT PURPLE (4225 4750);
FORCENOTE
B (80P)
(4225 4650) 0;
DISPLAY LEFT (4225 4650);
DISPLAY 1.021277 (4225 4650);
PAINT PURPLE (4225 4650);
FORCENOTE
CONN
(4225 4925) 0;
DISPLAY LEFT (4225 4925);
DISPLAY 1.021277 (4225 4925);
PAINT PURPLE (4225 4925);
FORCENOTE
C (64P)
(4225 4550) 0;
DISPLAY LEFT (4225 4550);
DISPLAY 1.021277 (4225 4550);
PAINT PURPLE (4225 4550);
FORCENOTE
TO CPU0
(5025 2400) 0;
DISPLAY LEFT (5025 2400);
DISPLAY 1.021277 (5025 2400);
PAINT PURPLE (5025 2400);
FORCENOTE
ROOM=IO_SLOT
(4150 400) 0;
DISPLAY LEFT (4150 400);
DISPLAY 2.000000 (4150 400);
PAINT PURPLE (4150 400);
FORCENOTE
61082-122402LF
(7625 4750) 0;
DISPLAY LEFT (7625 4750);
DISPLAY 1.021277 (7625 4750);
PAINT PURPLE (7625 4750);
FORCENOTE
(12MM STACK)
(7625 4850) 0;
DISPLAY LEFT (7625 4850);
DISPLAY 1.021277 (7625 4850);
PAINT PURPLE (7625 4850);
FORCENOTE
FCI RECPT # ON CC
(7625 4925) 0;
DISPLAY LEFT (7625 4925);
DISPLAY 1.021277 (7625 4925);
PAINT PURPLE (7625 4925);
FORCENOTE
FCI RECPT IPN ON CC
(8275 4925) 0;
DISPLAY LEFT (8275 4925);
DISPLAY 1.021277 (8275 4925);
PAINT PURPLE (8275 4925);
FORCENOTE
61082-121402LF
(6275 4750) 0;
DISPLAY LEFT (6275 4750);
DISPLAY 1.021277 (6275 4750);
PAINT PURPLE (6275 4750);
FORCENOTE
E67482-006
(6950 4650) 0;
DISPLAY LEFT (6950 4650);
DISPLAY 1.021277 (6950 4650);
PAINT PURPLE (6950 4650);
FORCENOTE
H87568-001
(6950 4550) 0;
DISPLAY LEFT (6950 4550);
DISPLAY 1.021277 (6950 4550);
PAINT PURPLE (6950 4550);
FORCENOTE
H87568-002
(8275 4550) 0;
DISPLAY LEFT (8275 4550);
DISPLAY 1.021277 (8275 4550);
PAINT PURPLE (8275 4550);
FORCENOTE
E67482-008
(8275 4650) 0;
DISPLAY LEFT (8275 4650);
DISPLAY 1.021277 (8275 4650);
PAINT PURPLE (8275 4650);
FORCENOTE
A28699-020
(8275 4750) 0;
DISPLAY LEFT (8275 4750);
DISPLAY 1.021277 (8275 4750);
PAINT PURPLE (8275 4750);
FORCENOTE
FROM CPU0
(10900 2325) 0;
DISPLAY LEFT (10900 2325);
DISPLAY 1.021277 (10900 2325);
PAINT PURPLE (10900 2325);
FORCENOTE
10135584-644402LF
(5400 4550) 0;
DISPLAY LEFT (5400 4550);
DISPLAY 1.021277 (5400 4550);
PAINT PURPLE (5400 4550);
FORCENOTE
(5MM STACK)
(4550 4850) 0;
DISPLAY LEFT (4550 4850);
DISPLAY 1.021277 (4550 4850);
PAINT PURPLE (4550 4850);
FORCENOTE
FCI PLUG # ON OCP MEZZ
(4550 4925) 0;
DISPLAY LEFT (4550 4925);
DISPLAY 1.021277 (4550 4925);
PAINT PURPLE (4550 4925);
FORCENOTE
MATED HT CONNECTOR P/NS
(4225 5025) 0;
DISPLAY LEFT (4225 5025);
DISPLAY 1.021277 (4225 5025);
PAINT PURPLE (4225 5025);
QUIT
